FILE_TYPE = MACRO_DRAWING;
SET COLOR_WIRE YELLOW;
SET COLOR_PROP MONO;
SET COLOR_DOT WHITE;
SET COLOR_ARC YELLOW;
SET COLOR_BODY GREEN;
SET COLOR_NOTE MONO;
SET PROP_DISPLAY VALUE;
SET PAGE_NUMBER P231;
FORCEADD CAP..1
(-7850 1000);
FORCEPROP 1 LASTPIN (-7850 900) $PN 2
J 0
(-7840 880);
DISPLAY 0.617021 (-7840 880);
PAINT GREEN (-7840 880);
FORCEPROP 1 LAST MATERIAL X6S
J 0
(-7800 900);
DISPLAY 0.617021 (-7800 900);
PAINT SKYBLUE (-7800 900);
FORCEPROP 1 LAST TOLERANCE 20%
J 0
(-7800 950);
DISPLAY 0.617021 (-7800 950);
PAINT SKYBLUE (-7800 950);
FORCEPROP 1 LAST PACK_TYPE 0603LF
J 0
(-7800 800);
DISPLAY 0.617021 (-7800 800);
PAINT SKYBLUE (-7800 800);
FORCEPROP 1 LAST PART_NUMBER E15431-001
J 0
(-7800 850);
DISPLAY 0.617021 (-7800 850);
PAINT BLUE (-7800 850);
FORCEPROP 1 LASTPIN (-7850 1100) $PN 1
J 0
(-7840 1080);
DISPLAY 0.617021 (-7840 1080);
PAINT GREEN (-7840 1080);
FORCEPROP 1 LAST VALUE 10UF
J 0
(-7800 1050);
DISPLAY 0.617021 (-7800 1050);
PAINT SKYBLUE (-7800 1050);
FORCEPROP 1 LAST LOCATION C6F6
J 0
(-7800 1100);
DISPLAY 0.617021 (-7800 1100);
PAINT AQUA (-7800 1100);
FORCEPROP 2 LAST CDS_LIB mstr_discrete
J 0
(-7850 1000);
PAINT ORANGE (-7850 1000);
DISPLAY INVISIBLE (-7850 1000);
FORCEPROP 1 LAST VOLTAGE 4V
J 0
(-7800 1000);
PAINT SKYBLUE (-7800 1000);
DISPLAY INVISIBLE (-7800 1000);
FORCEPROP 2 LAST CDS_LOCATION C6F6
J 0
(-7800 1100);
DISPLAY 0.617021 (-7800 1100);
PAINT AQUA (-7800 1100);
DISPLAY INVISIBLE (-7800 1100);
FORCEPROP 2 LAST CDS_SEC 1
J 0
(-7800 1200);
PAINT MONO (-7800 1200);
DISPLAY INVISIBLE (-7800 1200);
FORCEPROP 2 LAST $SEC 1
J 0
(-7800 1200);
PAINT MONO (-7800 1200);
DISPLAY INVISIBLE (-7800 1200);
FORCEPROP 2 LAST BOM_COST MEM_VRD_PVPP_AB
J 0
(-7800 1150);
PAINT MONO (-7800 1150);
DISPLAY INVISIBLE (-7800 1150);
FORCEPROP 1 LAST PATH I122
J 0
(-7800 1150);
DISPLAY 0.978723 (-7800 1150);
PAINT WHITE (-7800 1150);
DISPLAY INVISIBLE (-7800 1150);
FORCEPROP 2 LAST ROOM PVPP_KLM_VR
J 0
(-7800 1150);
PAINT MONO (-7800 1150);
DISPLAY INVISIBLE (-7800 1150);
FORCEADD PVPP_ABC..1
(-7850 1275);
FORCEPROP 3 LASTPIN (-7850 1225) SIG_NAME PVPP_ABC\g
J 0
(-7840 1235);
DISPLAY 0.659574 (-7840 1235);
PAINT MONO (-7840 1235);
DISPLAY INVISIBLE (-7840 1235);
FORCEPROP 1 LAST VOLTAGE 2.5V
J 0
(-7895 1232);
DISPLAY 0.340426 (-7895 1232);
PAINT SKYBLUE (-7895 1232);
DISPLAY INVISIBLE (-7895 1232);
FORCEPROP 1 LAST BODY_TYPE PLUMBING
J 0
(-7895 1232);
DISPLAY 0.340426 (-7895 1232);
PAINT GREEN (-7895 1232);
DISPLAY INVISIBLE (-7895 1232);
FORCEPROP 2 LAST CDS_LIB mstr_symbols
J 0
(-7850 1275);
PAINT ORANGE (-7850 1275);
DISPLAY INVISIBLE (-7850 1275);
FORCEPROP 2 LAST BOM_COST MEM_VRD_PVPP_AB
J 0
(-7775 1375);
PAINT MONO (-7775 1375);
DISPLAY INVISIBLE (-7775 1375);
FORCEPROP 1 LAST PATH I123
J 0
(-7800 1300);
DISPLAY 0.872340 (-7800 1300);
PAINT AQUA (-7800 1300);
DISPLAY INVISIBLE (-7800 1300);
FORCEPROP 1 LAST HDL_POWER PVPP_ABC
J 1
(-7850 1325);
DISPLAY 0.872340 (-7850 1325);
PAINT GREEN (-7850 1325);
DISPLAY INVISIBLE (-7850 1325);
FORCEPROP 2 LAST ROOM PVPP_KLM_VR
J 0
(-7600 1375);
PAINT ORANGE (-7600 1375);
DISPLAY INVISIBLE (-7600 1375);
FORCEADD CAP..1
(-7600 1000);
FORCEPROP 1 LAST TOLERANCE 20%
J 0
(-7550 950);
DISPLAY 0.617021 (-7550 950);
PAINT SKYBLUE (-7550 950);
FORCEPROP 1 LAST MATERIAL X6S
J 0
(-7550 900);
DISPLAY 0.617021 (-7550 900);
PAINT SKYBLUE (-7550 900);
FORCEPROP 1 LASTPIN (-7600 900) $PN 2
J 0
(-7590 880);
DISPLAY 0.617021 (-7590 880);
PAINT GREEN (-7590 880);
FORCEPROP 1 LAST PACK_TYPE 0603LF
J 0
(-7550 800);
DISPLAY 0.617021 (-7550 800);
PAINT SKYBLUE (-7550 800);
FORCEPROP 1 LAST PART_NUMBER E15431-001
J 0
(-7550 850);
DISPLAY 0.617021 (-7550 850);
PAINT BLUE (-7550 850);
FORCEPROP 1 LASTPIN (-7600 1100) $PN 1
J 0
(-7590 1080);
DISPLAY 0.617021 (-7590 1080);
PAINT GREEN (-7590 1080);
FORCEPROP 1 LAST VALUE 10UF
J 0
(-7550 1050);
DISPLAY 0.617021 (-7550 1050);
PAINT SKYBLUE (-7550 1050);
FORCEPROP 1 LAST LOCATION C4T6
J 0
(-7550 1100);
DISPLAY 0.617021 (-7550 1100);
PAINT AQUA (-7550 1100);
FORCEPROP 2 LAST CDS_LIB mstr_discrete
J 0
(-7600 1000);
PAINT ORANGE (-7600 1000);
DISPLAY INVISIBLE (-7600 1000);
FORCEPROP 1 LAST VOLTAGE 4V
J 0
(-7550 1000);
PAINT SKYBLUE (-7550 1000);
DISPLAY INVISIBLE (-7550 1000);
FORCEPROP 2 LAST ROOM PVPP_KLM_VR
J 0
(-7550 1150);
PAINT MONO (-7550 1150);
DISPLAY INVISIBLE (-7550 1150);
FORCEPROP 1 LAST PATH I124
J 0
(-7550 1150);
DISPLAY 0.978723 (-7550 1150);
PAINT WHITE (-7550 1150);
DISPLAY INVISIBLE (-7550 1150);
FORCEPROP 2 LAST CDS_LOCATION C4T6
J 0
(-7550 1100);
DISPLAY 0.617021 (-7550 1100);
PAINT AQUA (-7550 1100);
DISPLAY INVISIBLE (-7550 1100);
FORCEPROP 2 LAST $SEC 1
J 0
(-7550 1200);
PAINT MONO (-7550 1200);
DISPLAY INVISIBLE (-7550 1200);
FORCEPROP 2 LAST CDS_SEC 1
J 0
(-7550 1200);
PAINT MONO (-7550 1200);
DISPLAY INVISIBLE (-7550 1200);
FORCEPROP 2 LAST BOM_COST MEM_VRD_PVPP_AB
J 0
(-7550 1150);
PAINT MONO (-7550 1150);
DISPLAY INVISIBLE (-7550 1150);
FORCEADD CAP..1
(-7325 1000);
FORCEPROP 1 LAST TOLERANCE 20%
J 0
(-7275 950);
DISPLAY 0.617021 (-7275 950);
PAINT SKYBLUE (-7275 950);
FORCEPROP 1 LAST MATERIAL X6S
J 0
(-7275 900);
DISPLAY 0.617021 (-7275 900);
PAINT SKYBLUE (-7275 900);
FORCEPROP 1 LASTPIN (-7325 900) $PN 2
J 0
(-7315 880);
DISPLAY 0.617021 (-7315 880);
PAINT GREEN (-7315 880);
FORCEPROP 1 LASTPIN (-7325 1100) $PN 1
J 0
(-7315 1080);
DISPLAY 0.617021 (-7315 1080);
PAINT GREEN (-7315 1080);
FORCEPROP 1 LAST PACK_TYPE 0603LF
J 0
(-7275 800);
DISPLAY 0.617021 (-7275 800);
PAINT SKYBLUE (-7275 800);
FORCEPROP 1 LAST VALUE 10UF
J 0
(-7275 1050);
DISPLAY 0.617021 (-7275 1050);
PAINT SKYBLUE (-7275 1050);
FORCEPROP 1 LAST PART_NUMBER E15431-001
J 0
(-7275 850);
DISPLAY 0.617021 (-7275 850);
PAINT BLUE (-7275 850);
FORCEPROP 1 LAST LOCATION C4T5
J 0
(-7275 1100);
DISPLAY 0.617021 (-7275 1100);
PAINT AQUA (-7275 1100);
FORCEPROP 2 LAST CDS_LIB mstr_discrete
J 0
(-7325 1000);
PAINT ORANGE (-7325 1000);
DISPLAY INVISIBLE (-7325 1000);
FORCEPROP 1 LAST VOLTAGE 4V
J 0
(-7275 1000);
PAINT SKYBLUE (-7275 1000);
DISPLAY INVISIBLE (-7275 1000);
FORCEPROP 2 LAST CDS_LOCATION C4T5
J 0
(-7275 1100);
DISPLAY 0.617021 (-7275 1100);
PAINT AQUA (-7275 1100);
DISPLAY INVISIBLE (-7275 1100);
FORCEPROP 2 LAST ROOM PVPP_KLM_VR
J 0
(-7275 1150);
PAINT MONO (-7275 1150);
DISPLAY INVISIBLE (-7275 1150);
FORCEPROP 1 LAST PATH I125
J 0
(-7275 1150);
DISPLAY 0.978723 (-7275 1150);
PAINT WHITE (-7275 1150);
DISPLAY INVISIBLE (-7275 1150);
FORCEPROP 2 LAST CDS_SEC 1
J 0
(-7275 1200);
PAINT MONO (-7275 1200);
DISPLAY INVISIBLE (-7275 1200);
FORCEPROP 2 LAST $SEC 1
J 0
(-7275 1200);
PAINT MONO (-7275 1200);
DISPLAY INVISIBLE (-7275 1200);
FORCEPROP 2 LAST BOM_COST MEM_VRD_PVPP_AB
J 0
(-7275 1150);
PAINT MONO (-7275 1150);
DISPLAY INVISIBLE (-7275 1150);
FORCEADD CAP..1
(-7075 975);
FORCEPROP 1 LAST TOLERANCE 20%
J 0
(-7025 925);
DISPLAY 0.617021 (-7025 925);
PAINT SKYBLUE (-7025 925);
FORCEPROP 1 LAST MATERIAL X6S
J 0
(-7025 875);
DISPLAY 0.617021 (-7025 875);
PAINT SKYBLUE (-7025 875);
FORCEPROP 1 LASTPIN (-7075 875) $PN 2
J 0
(-7065 855);
DISPLAY 0.617021 (-7065 855);
PAINT GREEN (-7065 855);
FORCEPROP 1 LAST PACK_TYPE 0603LF
J 0
(-7025 775);
DISPLAY 0.617021 (-7025 775);
PAINT SKYBLUE (-7025 775);
FORCEPROP 1 LAST PART_NUMBER E15431-001
J 0
(-7025 825);
DISPLAY 0.617021 (-7025 825);
PAINT BLUE (-7025 825);
FORCEPROP 1 LASTPIN (-7075 1075) $PN 1
J 0
(-7065 1055);
DISPLAY 0.617021 (-7065 1055);
PAINT GREEN (-7065 1055);
FORCEPROP 1 LAST VALUE 10UF
J 0
(-7025 1025);
DISPLAY 0.617021 (-7025 1025);
PAINT SKYBLUE (-7025 1025);
FORCEPROP 1 LAST LOCATION C6G1
J 0
(-7025 1075);
DISPLAY 0.617021 (-7025 1075);
PAINT AQUA (-7025 1075);
FORCEPROP 1 LAST VOLTAGE 4V
J 0
(-7025 975);
PAINT SKYBLUE (-7025 975);
DISPLAY INVISIBLE (-7025 975);
FORCEPROP 2 LAST CDS_LIB mstr_discrete
J 0
(-7075 975);
PAINT ORANGE (-7075 975);
DISPLAY INVISIBLE (-7075 975);
FORCEPROP 2 LAST ROOM PVPP_KLM_VR
J 0
(-7025 1125);
PAINT MONO (-7025 1125);
DISPLAY INVISIBLE (-7025 1125);
FORCEPROP 1 LAST PATH I126
J 0
(-7025 1125);
DISPLAY 0.978723 (-7025 1125);
PAINT WHITE (-7025 1125);
DISPLAY INVISIBLE (-7025 1125);
FORCEPROP 2 LAST CDS_LOCATION C6G1
J 0
(-7025 1075);
DISPLAY 0.617021 (-7025 1075);
PAINT AQUA (-7025 1075);
DISPLAY INVISIBLE (-7025 1075);
FORCEPROP 2 LAST $SEC 1
J 0
(-7025 1175);
PAINT MONO (-7025 1175);
DISPLAY INVISIBLE (-7025 1175);
FORCEPROP 2 LAST CDS_SEC 1
J 0
(-7025 1175);
PAINT MONO (-7025 1175);
DISPLAY INVISIBLE (-7025 1175);
FORCEPROP 2 LAST BOM_COST MEM_VRD_PVPP_AB
J 0
(-7025 1125);
PAINT MONO (-7025 1125);
DISPLAY INVISIBLE (-7025 1125);
FORCEADD GND..1
(-6625 2200);
FORCEPROP 3 LASTPIN (-6625 2250) SIG_NAME GND\g
J 0
(-6615 2260);
DISPLAY 0.659574 (-6615 2260);
PAINT MONO (-6615 2260);
DISPLAY INVISIBLE (-6615 2260);
FORCEPROP 2 LAST ROOM PVPP_KLM_VR
J 0
(-7375 2275);
DISPLAY 1.042553 (-7375 2275);
PAINT GREEN (-7375 2275);
DISPLAY INVISIBLE (-7375 2275);
FORCEPROP 2 LAST BOM SYSB_CPLD
J 0
(-7375 2375);
DISPLAY 1.042553 (-7375 2375);
PAINT ORANGE (-7375 2375);
DISPLAY INVISIBLE (-7375 2375);
FORCEPROP 2 LAST BOM_COST PVPP_KLM_VR
J 0
(-7375 2325);
DISPLAY 1.042553 (-7375 2325);
PAINT WHITE (-7375 2325);
DISPLAY INVISIBLE (-7375 2325);
FORCEPROP 1 LAST BODY_TYPE PLUMBING
J 0
(-6670 2157);
DISPLAY 0.340426 (-6670 2157);
PAINT GREEN (-6670 2157);
DISPLAY INVISIBLE (-6670 2157);
FORCEPROP 1 LAST PATH I127
J 0
(-6550 2200);
DISPLAY 0.872340 (-6550 2200);
PAINT AQUA (-6550 2200);
DISPLAY INVISIBLE (-6550 2200);
FORCEPROP 2 LAST CDS_LIB mstr_symbols
J 0
(-6625 2200);
PAINT MONO (-6625 2200);
DISPLAY INVISIBLE (-6625 2200);
FORCEPROP 1 LAST SIZE 1B
J 0
(-6550 2150);
DISPLAY 0.680851 (-6550 2150);
PAINT ORANGE (-6550 2150);
DISPLAY INVISIBLE (-6550 2150);
FORCEPROP 1 LAST VOLTAGE 0
J 0
(-6625 2200);
PAINT SKYBLUE (-6625 2200);
DISPLAY INVISIBLE (-6625 2200);
FORCEPROP 1 LAST HDL_POWER GND
J 0
(-6625 2350);
DISPLAY 0.680851 (-6625 2350);
PAINT GREEN (-6625 2350);
DISPLAY INVISIBLE (-6625 2350);
FORCEADD CAP..1
(-6800 1000);
FORCEPROP 1 LAST TOLERANCE 20%
J 0
(-6750 950);
DISPLAY 0.617021 (-6750 950);
PAINT SKYBLUE (-6750 950);
FORCEPROP 1 LAST MATERIAL X6S
J 0
(-6750 900);
DISPLAY 0.617021 (-6750 900);
PAINT SKYBLUE (-6750 900);
FORCEPROP 1 LASTPIN (-6800 900) $PN 2
J 0
(-6790 880);
DISPLAY 0.617021 (-6790 880);
PAINT GREEN (-6790 880);
FORCEPROP 1 LAST PACK_TYPE 0603LF
J 0
(-6750 800);
DISPLAY 0.617021 (-6750 800);
PAINT SKYBLUE (-6750 800);
FORCEPROP 1 LAST PART_NUMBER E15431-001
J 0
(-6750 850);
DISPLAY 0.617021 (-6750 850);
PAINT BLUE (-6750 850);
FORCEPROP 1 LASTPIN (-6800 1100) $PN 1
J 0
(-6790 1080);
DISPLAY 0.617021 (-6790 1080);
PAINT GREEN (-6790 1080);
FORCEPROP 1 LAST VALUE 10UF
J 0
(-6750 1050);
DISPLAY 0.617021 (-6750 1050);
PAINT SKYBLUE (-6750 1050);
FORCEPROP 1 LAST LOCATION C6G2
J 0
(-6750 1100);
DISPLAY 0.617021 (-6750 1100);
PAINT AQUA (-6750 1100);
FORCEPROP 2 LAST CDS_LIB mstr_discrete
J 0
(-6800 1000);
PAINT ORANGE (-6800 1000);
DISPLAY INVISIBLE (-6800 1000);
FORCEPROP 1 LAST VOLTAGE 4V
J 0
(-6750 1000);
PAINT SKYBLUE (-6750 1000);
DISPLAY INVISIBLE (-6750 1000);
FORCEPROP 2 LAST ROOM PVPP_KLM_VR
J 0
(-6750 1150);
PAINT MONO (-6750 1150);
DISPLAY INVISIBLE (-6750 1150);
FORCEPROP 1 LAST PATH I128
J 0
(-6750 1150);
DISPLAY 0.978723 (-6750 1150);
PAINT WHITE (-6750 1150);
DISPLAY INVISIBLE (-6750 1150);
FORCEPROP 2 LAST CDS_LOCATION C6G2
J 0
(-6750 1100);
DISPLAY 0.617021 (-6750 1100);
PAINT AQUA (-6750 1100);
DISPLAY INVISIBLE (-6750 1100);
FORCEPROP 2 LAST $SEC 1
J 0
(-6750 1200);
PAINT MONO (-6750 1200);
DISPLAY INVISIBLE (-6750 1200);
FORCEPROP 2 LAST CDS_SEC 1
J 0
(-6750 1200);
PAINT MONO (-6750 1200);
DISPLAY INVISIBLE (-6750 1200);
FORCEPROP 2 LAST BOM_COST MEM_VRD_PVPP_AB
J 0
(-6750 1150);
PAINT MONO (-6750 1150);
DISPLAY INVISIBLE (-6750 1150);
FORCEADD CAP..1
(-6500 1000);
FORCEPROP 1 LASTPIN (-6500 900) $PN 2
J 0
(-6490 880);
DISPLAY 0.617021 (-6490 880);
PAINT GREEN (-6490 880);
FORCEPROP 1 LAST MATERIAL X6S
J 0
(-6450 900);
DISPLAY 0.617021 (-6450 900);
PAINT SKYBLUE (-6450 900);
FORCEPROP 1 LAST PACK_TYPE 0603LF
J 0
(-6450 800);
DISPLAY 0.617021 (-6450 800);
PAINT SKYBLUE (-6450 800);
FORCEPROP 1 LAST TOLERANCE 20%
J 0
(-6450 950);
DISPLAY 0.617021 (-6450 950);
PAINT SKYBLUE (-6450 950);
FORCEPROP 1 LAST PART_NUMBER E15431-001
J 0
(-6450 850);
DISPLAY 0.617021 (-6450 850);
PAINT BLUE (-6450 850);
FORCEPROP 1 LASTPIN (-6500 1100) $PN 1
J 0
(-6490 1080);
DISPLAY 0.617021 (-6490 1080);
PAINT GREEN (-6490 1080);
FORCEPROP 1 LAST VALUE 10UF
J 0
(-6450 1050);
DISPLAY 0.617021 (-6450 1050);
PAINT SKYBLUE (-6450 1050);
FORCEPROP 1 LAST LOCATION C4U2
J 0
(-6450 1100);
DISPLAY 0.617021 (-6450 1100);
PAINT AQUA (-6450 1100);
FORCEPROP 2 LAST CDS_LIB mstr_discrete
J 0
(-6500 1000);
PAINT ORANGE (-6500 1000);
DISPLAY INVISIBLE (-6500 1000);
FORCEPROP 1 LAST VOLTAGE 4V
J 0
(-6450 1000);
PAINT SKYBLUE (-6450 1000);
DISPLAY INVISIBLE (-6450 1000);
FORCEPROP 2 LAST CDS_LOCATION C4U2
J 0
(-6450 1100);
DISPLAY 0.617021 (-6450 1100);
PAINT AQUA (-6450 1100);
DISPLAY INVISIBLE (-6450 1100);
FORCEPROP 2 LAST BOM_COST MEM_VRD_PVPP_AB
J 0
(-6450 1150);
PAINT MONO (-6450 1150);
DISPLAY INVISIBLE (-6450 1150);
FORCEPROP 1 LAST PATH I129
J 0
(-6450 1150);
DISPLAY 0.978723 (-6450 1150);
PAINT WHITE (-6450 1150);
DISPLAY INVISIBLE (-6450 1150);
FORCEPROP 2 LAST ROOM PVPP_KLM_VR
J 0
(-6450 1150);
PAINT MONO (-6450 1150);
DISPLAY INVISIBLE (-6450 1150);
FORCEPROP 2 LAST CDS_SEC 1
J 0
(-6450 1200);
PAINT MONO (-6450 1200);
DISPLAY INVISIBLE (-6450 1200);
FORCEPROP 2 LAST $SEC 1
J 0
(-6450 1200);
PAINT MONO (-6450 1200);
DISPLAY INVISIBLE (-6450 1200);
FORCEADD CAP..1
(-6225 1000);
FORCEPROP 1 LASTPIN (-6225 900) $PN 2
J 0
(-6215 880);
DISPLAY 0.617021 (-6215 880);
PAINT GREEN (-6215 880);
FORCEPROP 1 LASTPIN (-6225 1100) $PN 1
J 0
(-6215 1080);
DISPLAY 0.617021 (-6215 1080);
PAINT GREEN (-6215 1080);
FORCEPROP 1 LAST MATERIAL X6S
J 0
(-6175 900);
DISPLAY 0.617021 (-6175 900);
PAINT SKYBLUE (-6175 900);
FORCEPROP 1 LAST PACK_TYPE 0603LF
J 0
(-6175 800);
DISPLAY 0.617021 (-6175 800);
PAINT SKYBLUE (-6175 800);
FORCEPROP 1 LAST TOLERANCE 20%
J 0
(-6175 950);
DISPLAY 0.617021 (-6175 950);
PAINT SKYBLUE (-6175 950);
FORCEPROP 1 LAST VALUE 10UF
J 0
(-6175 1050);
DISPLAY 0.617021 (-6175 1050);
PAINT SKYBLUE (-6175 1050);
FORCEPROP 1 LAST PART_NUMBER E15431-001
J 0
(-6175 850);
DISPLAY 0.617021 (-6175 850);
PAINT BLUE (-6175 850);
FORCEPROP 1 LAST LOCATION C4U1
J 0
(-6175 1100);
DISPLAY 0.617021 (-6175 1100);
PAINT AQUA (-6175 1100);
FORCEPROP 2 LAST CDS_LIB mstr_discrete
J 0
(-6225 1000);
PAINT MONO (-6225 1000);
DISPLAY INVISIBLE (-6225 1000);
FORCEPROP 1 LAST VOLTAGE 4V
J 0
(-6175 1000);
PAINT SKYBLUE (-6175 1000);
DISPLAY INVISIBLE (-6175 1000);
FORCEPROP 2 LAST CDS_LOCATION C4U1
J 0
(-6175 1100);
DISPLAY 0.617021 (-6175 1100);
PAINT AQUA (-6175 1100);
DISPLAY INVISIBLE (-6175 1100);
FORCEPROP 1 LAST PATH I130
J 0
(-6175 1150);
DISPLAY 0.978723 (-6175 1150);
PAINT WHITE (-6175 1150);
DISPLAY INVISIBLE (-6175 1150);
FORCEPROP 2 LAST BOM_COST MEM_VRD_PVPP_AB
J 0
(-6175 1150);
PAINT MONO (-6175 1150);
DISPLAY INVISIBLE (-6175 1150);
FORCEPROP 2 LAST ROOM PVPP_KLM_VR
J 0
(-6175 1150);
PAINT MONO (-6175 1150);
DISPLAY INVISIBLE (-6175 1150);
FORCEPROP 2 LAST CDS_SEC 1
J 0
(-6175 1200);
PAINT MONO (-6175 1200);
DISPLAY INVISIBLE (-6175 1200);
FORCEPROP 2 LAST $SEC 1
J 0
(-6175 1200);
PAINT MONO (-6175 1200);
DISPLAY INVISIBLE (-6175 1200);
FORCEADD CAP..1
(-5925 1000);
FORCEPROP 1 LASTPIN (-5925 900) $PN 2
J 0
(-5915 880);
DISPLAY 0.617021 (-5915 880);
PAINT GREEN (-5915 880);
FORCEPROP 1 LAST MATERIAL X6S
J 0
(-5875 900);
DISPLAY 0.617021 (-5875 900);
PAINT SKYBLUE (-5875 900);
FORCEPROP 1 LAST PACK_TYPE 0603LF
J 0
(-5875 800);
DISPLAY 0.617021 (-5875 800);
PAINT SKYBLUE (-5875 800);
FORCEPROP 1 LAST TOLERANCE 20%
J 0
(-5875 950);
DISPLAY 0.617021 (-5875 950);
PAINT SKYBLUE (-5875 950);
FORCEPROP 1 LAST PART_NUMBER E15431-001
J 0
(-5875 850);
DISPLAY 0.617021 (-5875 850);
PAINT BLUE (-5875 850);
FORCEPROP 1 LASTPIN (-5925 1100) $PN 1
J 0
(-5915 1080);
DISPLAY 0.617021 (-5915 1080);
PAINT GREEN (-5915 1080);
FORCEPROP 1 LAST VALUE 10UF
J 0
(-5875 1050);
DISPLAY 0.617021 (-5875 1050);
PAINT SKYBLUE (-5875 1050);
FORCEPROP 1 LAST LOCATION C6G4
J 0
(-5875 1100);
DISPLAY 0.617021 (-5875 1100);
PAINT AQUA (-5875 1100);
FORCEPROP 2 LAST CDS_LIB mstr_discrete
J 0
(-5925 1000);
PAINT MONO (-5925 1000);
DISPLAY INVISIBLE (-5925 1000);
FORCEPROP 1 LAST VOLTAGE 4V
J 0
(-5875 1000);
PAINT SKYBLUE (-5875 1000);
DISPLAY INVISIBLE (-5875 1000);
FORCEPROP 2 LAST ROOM PVPP_KLM_VR
J 0
(-5875 1150);
PAINT MONO (-5875 1150);
DISPLAY INVISIBLE (-5875 1150);
FORCEPROP 1 LAST PATH I131
J 0
(-5875 1150);
DISPLAY 0.978723 (-5875 1150);
PAINT WHITE (-5875 1150);
DISPLAY INVISIBLE (-5875 1150);
FORCEPROP 2 LAST CDS_LOCATION C6G4
J 0
(-5875 1100);
DISPLAY 0.617021 (-5875 1100);
PAINT AQUA (-5875 1100);
DISPLAY INVISIBLE (-5875 1100);
FORCEPROP 2 LAST $SEC 1
J 0
(-5875 1200);
PAINT MONO (-5875 1200);
DISPLAY INVISIBLE (-5875 1200);
FORCEPROP 2 LAST CDS_SEC 1
J 0
(-5875 1200);
PAINT MONO (-5875 1200);
DISPLAY INVISIBLE (-5875 1200);
FORCEPROP 2 LAST BOM_COST MEM_VRD_PVPP_AB
J 0
(-5875 1150);
PAINT MONO (-5875 1150);
DISPLAY INVISIBLE (-5875 1150);
FORCEADD AGND_SCSI..1
(-6175 2325);
FORCEPROP 3 LASTPIN (-6175 2375) SIG_NAME AGND_PVPP_ABC\g
J 0
(-6165 2385);
DISPLAY 0.659574 (-6165 2385);
PAINT MONO (-6165 2385);
DISPLAY INVISIBLE (-6165 2385);
FORCEPROP 1 LAST HDL_POWER AGND_PVPP_ABC
J 1
(-6150 2250);
DISPLAY 0.617021 (-6150 2250);
PAINT GREEN (-6150 2250);
FORCEPROP 1 LAST VOLTAGE 0.0V
J 0
(-6220 2282);
DISPLAY 0.340426 (-6220 2282);
PAINT SKYBLUE (-6220 2282);
DISPLAY INVISIBLE (-6220 2282);
FORCEPROP 1 LAST BODY_TYPE PLUMBING
J 0
(-6220 2282);
DISPLAY 0.340426 (-6220 2282);
PAINT GREEN (-6220 2282);
DISPLAY INVISIBLE (-6220 2282);
FORCEPROP 2 LAST ROOM PVPP_KLM_VR
J 0
(-6325 2275);
DISPLAY 1.042553 (-6325 2275);
PAINT GREEN (-6325 2275);
DISPLAY INVISIBLE (-6325 2275);
FORCEPROP 2 LAST BOM_COST PVPP_KLM_VR
J 0
(-6325 2275);
DISPLAY 1.042553 (-6325 2275);
PAINT WHITE (-6325 2275);
DISPLAY INVISIBLE (-6325 2275);
FORCEPROP 2 LAST CDS_LIB mstr_symbols
J 0
(-6175 2325);
PAINT MONO (-6175 2325);
DISPLAY INVISIBLE (-6175 2325);
FORCEPROP 1 LAST PATH I132
J 0
(-6100 2325);
DISPLAY 0.872340 (-6100 2325);
PAINT AQUA (-6100 2325);
DISPLAY INVISIBLE (-6100 2325);
FORCEADD RES..2
R 2
(-4400 1900);
FORCEPROP 1 LAST PART_NUMBER G21796-242
J 2
(-4440 1775);
DISPLAY 0.617021 (-4440 1775);
PAINT BLUE (-4440 1775);
FORCEPROP 1 LAST PACK_TYPE 0402
J 2
(-4440 1725);
DISPLAY 0.617021 (-4440 1725);
PAINT SKYBLUE (-4440 1725);
FORCEPROP 1 LAST WATTAGE 1/16W
J 2
(-4440 1875);
DISPLAY 0.617021 (-4440 1875);
PAINT SKYBLUE (-4440 1875);
FORCEPROP 1 LAST MATERIAL CHIP
J 2
(-4440 1825);
DISPLAY 0.617021 (-4440 1825);
PAINT SKYBLUE (-4440 1825);
FORCEPROP 1 LAST TOLERANCE 1.0%
J 2
(-4445 1925);
DISPLAY 0.617021 (-4445 1925);
PAINT SKYBLUE (-4445 1925);
FORCEPROP 1 LAST VALUE 7.87K
J 2
(-4445 1975);
DISPLAY 0.617021 (-4445 1975);
PAINT SKYBLUE (-4445 1975);
FORCEPROP 1 LASTPIN (-4400 1800) $PN 2
J 2
(-4405 1810);
DISPLAY 0.617021 (-4405 1810);
PAINT WHITE (-4405 1810);
FORCEPROP 1 LASTPIN (-4400 2000) $PN 1
J 2
(-4405 1962);
DISPLAY 0.617021 (-4405 1962);
PAINT WHITE (-4405 1962);
FORCEPROP 1 LAST LOCATION R7F15
J 2
(-4445 2025);
DISPLAY 0.617021 (-4445 2025);
PAINT AQUA (-4445 2025);
FORCEPROP 2 LAST ROOM PVPP_KLM_VR
J 2
(-4400 1900);
PAINT GREEN (-4400 1900);
DISPLAY INVISIBLE (-4400 1900);
FORCEPROP 2 LAST BOM_COST PVPP_KLM_VR
J 2
(-4400 1900);
PAINT WHITE (-4400 1900);
DISPLAY INVISIBLE (-4400 1900);
FORCEPROP 2 LAST CDS_LIB mstr_discrete
J 2
(-4400 1900);
PAINT MONO (-4400 1900);
DISPLAY INVISIBLE (-4400 1900);
FORCEPROP 2 LAST CDS_LOCATION R7F15
J 2
(-4445 2025);
DISPLAY 0.617021 (-4445 2025);
PAINT AQUA (-4445 2025);
DISPLAY INVISIBLE (-4445 2025);
FORCEPROP 1 LAST PATH I134
J 2
(-4450 2075);
DISPLAY 0.978723 (-4450 2075);
PAINT WHITE (-4450 2075);
DISPLAY INVISIBLE (-4450 2075);
FORCEPROP 2 LAST $SEC 1
J 0
(-4450 2125);
DISPLAY 0.680851 (-4450 2125);
PAINT MONO (-4450 2125);
DISPLAY INVISIBLE (-4450 2125);
FORCEPROP 2 LAST CDS_SEC 1
J 2
(-4300 2275);
DISPLAY 1.042553 (-4300 2275);
PAINT ORANGE (-4300 2275);
DISPLAY INVISIBLE (-4300 2275);
FORCEADD OFFPAGE..1
(-7050 3075);
FORCEPROP 2 LAST $XR0 191 
J 0
(-7302 3075);
DISPLAY 0.638298 (-7302 3075);
PAINT MONO (-7302 3075);
FORCEPROP 2 LAST $XR1 232 
J 0
(-7422 3075);
DISPLAY 0.638298 (-7422 3075);
PAINT MONO (-7422 3075);
FORCEPROP 2 LAST PATH I135
J 0
(-7300 3125);
DISPLAY 1.021277 (-7300 3125);
PAINT ORANGE (-7300 3125);
DISPLAY INVISIBLE (-7300 3125);
FORCEPROP 2 LAST BOM_COST PVPP_KLM_VR
J 0
(-7875 3150);
DISPLAY 1.042553 (-7875 3150);
PAINT WHITE (-7875 3150);
DISPLAY INVISIBLE (-7875 3150);
FORCEPROP 2 LAST ROOM PVPP_KLM_VR
J 0
(-7600 3150);
DISPLAY 1.042553 (-7600 3150);
PAINT GREEN (-7600 3150);
DISPLAY INVISIBLE (-7600 3150);
FORCEPROP 1 LAST COMMENT_BODY TRUE
J 0
(-6925 2975);
DISPLAY 0.872340 (-6925 2975);
PAINT PEACH (-6925 2975);
DISPLAY INVISIBLE (-6925 2975);
FORCEPROP 1 LAST OFFPAGE TRUE
J 0
(-6725 2950);
PAINT GREEN (-6725 2950);
DISPLAY INVISIBLE (-6725 2950);
FORCEPROP 2 LAST CDS_LIB mstr_standard
J 0
(-7050 3075);
PAINT MONO (-7050 3075);
DISPLAY INVISIBLE (-7050 3075);
FORCEPROP 0 LAST TOLERANCE 1%
J 0
(-7000 3150);
PAINT SKYBLUE (-7000 3150);
DISPLAY INVISIBLE (-7000 3150);
FORCEADD RES..2
(-6625 2450);
FORCEPROP 1 LAST PACK_TYPE 0402
J 0
(-6585 2275);
DISPLAY 0.617021 (-6585 2275);
PAINT SKYBLUE (-6585 2275);
FORCEPROP 1 LASTPIN (-6625 2350) $PN 2
J 0
(-6620 2360);
DISPLAY 0.617021 (-6620 2360);
PAINT WHITE (-6620 2360);
FORCEPROP 1 LASTPIN (-6625 2550) $PN 1
J 0
(-6620 2512);
DISPLAY 0.617021 (-6620 2512);
PAINT WHITE (-6620 2512);
FORCEPROP 1 LAST TOLERANCE 1%
J 0
(-6580 2475);
DISPLAY 0.617021 (-6580 2475);
PAINT SKYBLUE (-6580 2475);
FORCEPROP 1 LAST MATERIAL CHIP
J 0
(-6585 2375);
DISPLAY 0.617021 (-6585 2375);
PAINT SKYBLUE (-6585 2375);
FORCEPROP 1 LAST WATTAGE 1/16W
J 0
(-6585 2425);
DISPLAY 0.617021 (-6585 2425);
PAINT SKYBLUE (-6585 2425);
FORCEPROP 1 LAST VALUE 10.0K
J 0
(-6580 2525);
DISPLAY 0.617021 (-6580 2525);
PAINT SKYBLUE (-6580 2525);
FORCEPROP 1 LAST PART_NUMBER G21796-016
J 0
(-6610 2325);
DISPLAY 0.617021 (-6610 2325);
PAINT BLUE (-6610 2325);
FORCEPROP 1 LAST LOCATION R7F14
J 0
(-6580 2575);
DISPLAY 0.617021 (-6580 2575);
PAINT AQUA (-6580 2575);
FORCEPROP 2 LAST CDS_LIB mstr_discrete
J 0
(-6625 2450);
PAINT MONO (-6625 2450);
DISPLAY INVISIBLE (-6625 2450);
FORCEPROP 2 LAST ROOM PVPP_KLM_VR
J 0
(-6575 2675);
DISPLAY 1.042553 (-6575 2675);
PAINT GREEN (-6575 2675);
DISPLAY INVISIBLE (-6575 2675);
FORCEPROP 1 LAST PATH I136
J 0
(-6575 2625);
DISPLAY 0.978723 (-6575 2625);
PAINT WHITE (-6575 2625);
DISPLAY INVISIBLE (-6575 2625);
FORCEPROP 2 LAST CDS_LOCATION R7F14
J 0
(-6580 2575);
DISPLAY 0.617021 (-6580 2575);
PAINT AQUA (-6580 2575);
DISPLAY INVISIBLE (-6580 2575);
FORCEPROP 2 LAST $SEC 1
J 0
(-6575 2675);
DISPLAY 0.680851 (-6575 2675);
PAINT MONO (-6575 2675);
DISPLAY INVISIBLE (-6575 2675);
FORCEPROP 2 LAST CDS_SEC 1
J 0
(-6575 2675);
DISPLAY 1.042553 (-6575 2675);
PAINT ORANGE (-6575 2675);
DISPLAY INVISIBLE (-6575 2675);
FORCEPROP 2 LAST BOM_COST PVPP_KLM_VR
J 0
(-6575 2675);
DISPLAY 1.042553 (-6575 2675);
PAINT WHITE (-6575 2675);
DISPLAY INVISIBLE (-6575 2675);
FORCEPROP 0 LAST BOM SYSB_CPLD
J 0
(-6575 2775);
DISPLAY 1.042553 (-6575 2775);
PAINT ORANGE (-6575 2775);
DISPLAY INVISIBLE (-6575 2775);
FORCEADD CAP..1
R 2
(-6175 2650);
FORCEPROP 1 LAST PART_NUMBER A36096-046
J 2
(-6200 2500);
DISPLAY 0.617021 (-6200 2500);
PAINT BLUE (-6200 2500);
FORCEPROP 1 LAST PACK_TYPE 0402LF
J 2
(-6225 2450);
DISPLAY 0.617021 (-6225 2450);
PAINT SKYBLUE (-6225 2450);
FORCEPROP 1 LASTPIN (-6175 2550) $PN 2
J 2
(-6185 2530);
DISPLAY 0.617021 (-6185 2530);
PAINT WHITE (-6185 2530);
FORCEPROP 1 LAST MATERIAL EMPTY
J 2
(-6225 2550);
DISPLAY 0.617021 (-6225 2550);
PAINT RED (-6225 2550);
FORCEPROP 1 LAST VOLTAGE 50V
J 2
(-6225 2650);
DISPLAY 0.617021 (-6225 2650);
PAINT SKYBLUE (-6225 2650);
FORCEPROP 1 LAST TOLERANCE 10%
J 2
(-6225 2600);
DISPLAY 0.617021 (-6225 2600);
PAINT SKYBLUE (-6225 2600);
FORCEPROP 1 LAST VALUE 1000PF
J 2
(-6225 2700);
DISPLAY 0.617021 (-6225 2700);
PAINT SKYBLUE (-6225 2700);
FORCEPROP 1 LAST LOCATION C7F8
J 2
(-6225 2750);
DISPLAY 0.617021 (-6225 2750);
PAINT AQUA (-6225 2750);
FORCEPROP 1 LASTPIN (-6175 2750) $PN 1
J 2
(-6185 2730);
DISPLAY 0.617021 (-6185 2730);
PAINT WHITE (-6185 2730);
FORCEPROP 2 LAST ROOM PVPP_KLM_VR
J 2
(-6175 2650);
PAINT GREEN (-6175 2650);
DISPLAY INVISIBLE (-6175 2650);
FORCEPROP 2 LAST BOM_COST PVPP_KLM_VR
J 2
(-6175 2650);
PAINT WHITE (-6175 2650);
DISPLAY INVISIBLE (-6175 2650);
FORCEPROP 2 LAST CDS_LIB mstr_discrete
J 2
(-6175 2650);
PAINT MONO (-6175 2650);
DISPLAY INVISIBLE (-6175 2650);
FORCEPROP 2 LAST CDS_LOCATION C7F8
J 2
(-6225 2750);
DISPLAY 0.617021 (-6225 2750);
PAINT AQUA (-6225 2750);
DISPLAY INVISIBLE (-6225 2750);
FORCEPROP 1 LAST PATH I140
J 2
(-6225 2800);
DISPLAY 0.978723 (-6225 2800);
PAINT WHITE (-6225 2800);
DISPLAY INVISIBLE (-6225 2800);
FORCEPROP 2 LAST $SEC 1
J 2
(-6225 2850);
DISPLAY 0.680851 (-6225 2850);
PAINT MONO (-6225 2850);
DISPLAY INVISIBLE (-6225 2850);
FORCEPROP 2 LAST CDS_SEC 1
J 2
(-6225 2850);
DISPLAY 1.042553 (-6225 2850);
PAINT ORANGE (-6225 2850);
DISPLAY INVISIBLE (-6225 2850);
FORCEPROP 0 LAST REUSE_ID 1
J 2
(-6225 2850);
DISPLAY 1.042553 (-6225 2850);
PAINT ORANGE (-6225 2850);
DISPLAY INVISIBLE (-6225 2850);
FORCEPROP 0 LAST FIN VR_1P2
J 2
(-6225 2950);
PAINT ORANGE (-6225 2950);
DISPLAY INVISIBLE (-6225 2950);
FORCEADD GND..1
(-3525 725);
FORCEPROP 3 LASTPIN (-3525 775) SIG_NAME GND\g
J 0
(-3515 785);
DISPLAY 0.659574 (-3515 785);
PAINT MONO (-3515 785);
DISPLAY INVISIBLE (-3515 785);
FORCEPROP 2 LAST ROOM PVPP_KLM_VR
J 0
(-4175 875);
PAINT GREEN (-4175 875);
DISPLAY INVISIBLE (-4175 875);
FORCEPROP 2 LAST BOM_COST PVPP_KLM_VR
J 0
(-4425 875);
DISPLAY 1.042553 (-4425 875);
PAINT WHITE (-4425 875);
DISPLAY INVISIBLE (-4425 875);
FORCEPROP 1 LAST PATH I141
J 0
(-3450 725);
DISPLAY 0.872340 (-3450 725);
PAINT AQUA (-3450 725);
DISPLAY INVISIBLE (-3450 725);
FORCEPROP 1 LAST BODY_TYPE PLUMBING
J 0
(-3570 682);
DISPLAY 0.340426 (-3570 682);
PAINT GREEN (-3570 682);
DISPLAY INVISIBLE (-3570 682);
FORCEPROP 1 LAST SIZE 1B
J 0
(-3450 750);
DISPLAY 0.893617 (-3450 750);
PAINT GREEN (-3450 750);
DISPLAY INVISIBLE (-3450 750);
FORCEPROP 1 LAST VOLTAGE 0
J 0
(-3525 800);
PAINT SKYBLUE (-3525 800);
DISPLAY INVISIBLE (-3525 800);
FORCEPROP 2 LAST CDS_LIB mstr_symbols
J 0
(-3525 800);
PAINT MONO (-3525 800);
DISPLAY INVISIBLE (-3525 800);
FORCEPROP 1 LAST HDL_POWER GND
J 0
(-3525 950);
DISPLAY 0.893617 (-3525 950);
PAINT GREEN (-3525 950);
DISPLAY INVISIBLE (-3525 950);
FORCEADD CAP..1
(-3525 975);
FORCEPROP 1 LASTPIN (-3525 875) $PN 2
J 0
(-3515 855);
DISPLAY 0.617021 (-3515 855);
PAINT WHITE (-3515 855);
FORCEPROP 1 LAST MATERIAL X7R
J 0
(-3475 875);
DISPLAY 0.617021 (-3475 875);
PAINT SKYBLUE (-3475 875);
FORCEPROP 1 LAST VOLTAGE 50V
J 0
(-3475 975);
DISPLAY 0.617021 (-3475 975);
PAINT SKYBLUE (-3475 975);
FORCEPROP 1 LAST TOLERANCE 10%
J 0
(-3475 925);
DISPLAY 0.617021 (-3475 925);
PAINT SKYBLUE (-3475 925);
FORCEPROP 1 LAST PACK_TYPE 0402LF
J 0
(-3475 825);
DISPLAY 0.617021 (-3475 825);
PAINT SKYBLUE (-3475 825);
FORCEPROP 1 LAST PART_NUMBER A36096-046
J 0
(-3475 775);
DISPLAY 0.617021 (-3475 775);
PAINT BLUE (-3475 775);
FORCEPROP 1 LASTPIN (-3525 1075) $PN 1
J 0
(-3515 1055);
DISPLAY 0.617021 (-3515 1055);
PAINT WHITE (-3515 1055);
FORCEPROP 1 LAST LOCATION C7F11
J 0
(-3475 1075);
DISPLAY 0.617021 (-3475 1075);
PAINT AQUA (-3475 1075);
FORCEPROP 1 LAST VALUE 1000PF
J 0
(-3475 1025);
DISPLAY 0.617021 (-3475 1025);
PAINT SKYBLUE (-3475 1025);
FORCEPROP 2 LAST ROOM PVPP_KLM_VR
J 0
(-3525 975);
PAINT GREEN (-3525 975);
DISPLAY INVISIBLE (-3525 975);
FORCEPROP 2 LAST CDS_LIB mstr_discrete
J 2
(-3525 975);
PAINT MONO (-3525 975);
DISPLAY INVISIBLE (-3525 975);
FORCEPROP 2 LAST BOM_COST PVPP_KLM_VR
J 0
(-3525 975);
PAINT WHITE (-3525 975);
DISPLAY INVISIBLE (-3525 975);
FORCEPROP 2 LAST CDS_LOCATION C7F11
J 0
(-3475 1075);
DISPLAY 0.617021 (-3475 1075);
PAINT AQUA (-3475 1075);
DISPLAY INVISIBLE (-3475 1075);
FORCEPROP 1 LAST PATH I142
J 0
(-3475 1125);
DISPLAY 0.978723 (-3475 1125);
PAINT WHITE (-3475 1125);
DISPLAY INVISIBLE (-3475 1125);
FORCEPROP 2 LAST $SEC 1
J 2
(-3475 1175);
DISPLAY 0.680851 (-3475 1175);
PAINT MONO (-3475 1175);
DISPLAY INVISIBLE (-3475 1175);
FORCEPROP 2 LAST CDS_SEC 1
J 2
(-3475 1175);
DISPLAY 1.042553 (-3475 1175);
PAINT ORANGE (-3475 1175);
DISPLAY INVISIBLE (-3475 1175);
FORCEPROP 2 LAST REUSE_ID 17
J 0
(-3475 1175);
DISPLAY 1.042553 (-3475 1175);
PAINT ORANGE (-3475 1175);
DISPLAY INVISIBLE (-3475 1175);
FORCEADD RES..2
(-3875 1500);
FORCEPROP 1 LASTPIN (-3875 1400) $PN 2
J 0
(-3870 1410);
DISPLAY 0.617021 (-3870 1410);
PAINT WHITE (-3870 1410);
FORCEPROP 1 LAST PACK_TYPE 0402
J 0
(-3835 1325);
DISPLAY 0.617021 (-3835 1325);
PAINT SKYBLUE (-3835 1325);
FORCEPROP 1 LAST MATERIAL CHIP
J 0
(-3835 1425);
DISPLAY 0.617021 (-3835 1425);
PAINT SKYBLUE (-3835 1425);
FORCEPROP 1 LAST WATTAGE 1/16W
J 0
(-3835 1475);
DISPLAY 0.617021 (-3835 1475);
PAINT SKYBLUE (-3835 1475);
FORCEPROP 1 LAST TOLERANCE 1%
J 0
(-3830 1525);
DISPLAY 0.617021 (-3830 1525);
PAINT SKYBLUE (-3830 1525);
FORCEPROP 1 LASTPIN (-3875 1600) $PN 1
J 0
(-3870 1562);
DISPLAY 0.617021 (-3870 1562);
PAINT WHITE (-3870 1562);
FORCEPROP 1 LAST VALUE 1.00K
J 0
(-3830 1575);
DISPLAY 0.617021 (-3830 1575);
PAINT SKYBLUE (-3830 1575);
FORCEPROP 1 LAST LOCATION R7F19
J 0
(-3830 1625);
DISPLAY 0.617021 (-3830 1625);
PAINT AQUA (-3830 1625);
FORCEPROP 1 LAST PART_NUMBER G21796-026
J 0
(-3835 1375);
DISPLAY 0.617021 (-3835 1375);
PAINT BLUE (-3835 1375);
FORCEPROP 2 LAST CDS_LIB mstr_discrete
J 0
(-3875 1500);
PAINT MONO (-3875 1500);
DISPLAY INVISIBLE (-3875 1500);
FORCEPROP 2 LAST ROOM PVPP_KLM_VR
J 0
(-3815 1665);
PAINT GREEN (-3815 1665);
DISPLAY INVISIBLE (-3815 1665);
FORCEPROP 1 LAST PATH I143
J 0
(-3825 1675);
DISPLAY 0.978723 (-3825 1675);
PAINT WHITE (-3825 1675);
DISPLAY INVISIBLE (-3825 1675);
FORCEPROP 2 LAST CDS_LOCATION R7F19
J 0
(-3830 1625);
DISPLAY 0.617021 (-3830 1625);
PAINT AQUA (-3830 1625);
DISPLAY INVISIBLE (-3830 1625);
FORCEPROP 2 LAST SEC 1
J 0
(-3825 1725);
DISPLAY 0.680851 (-3825 1725);
PAINT MONO (-3825 1725);
DISPLAY INVISIBLE (-3825 1725);
FORCEPROP 2 LAST REUSE_ID 21
J 0
(-3825 1725);
DISPLAY 1.042553 (-3825 1725);
PAINT ORANGE (-3825 1725);
DISPLAY INVISIBLE (-3825 1725);
FORCEPROP 2 LAST BOM_COST PVPP_KLM_VR
J 0
(-3815 1690);
DISPLAY 1.042553 (-3815 1690);
PAINT WHITE (-3815 1690);
DISPLAY INVISIBLE (-3815 1690);
FORCEPROP 2 LAST SEC_TYPE 0402
J 0
(-3825 1725);
DISPLAY 1.042553 (-3825 1725);
PAINT ORANGE (-3825 1725);
DISPLAY INVISIBLE (-3825 1725);
FORCEADD CAP..1
(-5625 1000);
FORCEPROP 1 LASTPIN (-5625 900) $PN 2
J 0
(-5615 880);
DISPLAY 0.617021 (-5615 880);
PAINT GREEN (-5615 880);
FORCEPROP 1 LAST MATERIAL X6S
J 0
(-5575 900);
DISPLAY 0.617021 (-5575 900);
PAINT SKYBLUE (-5575 900);
FORCEPROP 1 LAST PACK_TYPE 0603LF
J 0
(-5575 800);
DISPLAY 0.617021 (-5575 800);
PAINT SKYBLUE (-5575 800);
FORCEPROP 1 LAST TOLERANCE 20%
J 0
(-5575 950);
DISPLAY 0.617021 (-5575 950);
PAINT SKYBLUE (-5575 950);
FORCEPROP 1 LAST PART_NUMBER E15431-001
J 0
(-5575 850);
DISPLAY 0.617021 (-5575 850);
PAINT BLUE (-5575 850);
FORCEPROP 1 LASTPIN (-5625 1100) $PN 1
J 0
(-5615 1080);
DISPLAY 0.617021 (-5615 1080);
PAINT GREEN (-5615 1080);
FORCEPROP 1 LAST VALUE 10UF
J 0
(-5575 1050);
DISPLAY 0.617021 (-5575 1050);
PAINT SKYBLUE (-5575 1050);
FORCEPROP 1 LAST LOCATION C6G5
J 0
(-5575 1100);
DISPLAY 0.617021 (-5575 1100);
PAINT AQUA (-5575 1100);
FORCEPROP 2 LAST CDS_LIB mstr_discrete
J 0
(-5625 1000);
PAINT MONO (-5625 1000);
DISPLAY INVISIBLE (-5625 1000);
FORCEPROP 1 LAST VOLTAGE 4V
J 0
(-5575 1000);
PAINT SKYBLUE (-5575 1000);
DISPLAY INVISIBLE (-5575 1000);
FORCEPROP 2 LAST ROOM PVPP_KLM_VR
J 0
(-5575 1150);
PAINT MONO (-5575 1150);
DISPLAY INVISIBLE (-5575 1150);
FORCEPROP 1 LAST PATH I145
J 0
(-5575 1150);
DISPLAY 0.978723 (-5575 1150);
PAINT WHITE (-5575 1150);
DISPLAY INVISIBLE (-5575 1150);
FORCEPROP 2 LAST CDS_LOCATION C6G5
J 0
(-5575 1100);
DISPLAY 0.617021 (-5575 1100);
PAINT AQUA (-5575 1100);
DISPLAY INVISIBLE (-5575 1100);
FORCEPROP 2 LAST $SEC 1
J 0
(-5575 1200);
PAINT MONO (-5575 1200);
DISPLAY INVISIBLE (-5575 1200);
FORCEPROP 2 LAST CDS_SEC 1
J 0
(-5575 1200);
PAINT MONO (-5575 1200);
DISPLAY INVISIBLE (-5575 1200);
FORCEPROP 2 LAST BOM_COST MEM_VRD_PVPP_AB
J 0
(-5575 1150);
PAINT MONO (-5575 1150);
DISPLAY INVISIBLE (-5575 1150);
FORCEADD CAP..1
(-5350 975);
FORCEPROP 1 LAST TOLERANCE 20%
J 0
(-5300 925);
DISPLAY 0.617021 (-5300 925);
PAINT SKYBLUE (-5300 925);
FORCEPROP 1 LAST PACK_TYPE 0603LF
J 0
(-5300 775);
DISPLAY 0.617021 (-5300 775);
PAINT SKYBLUE (-5300 775);
FORCEPROP 1 LAST MATERIAL X6S
J 0
(-5300 875);
DISPLAY 0.617021 (-5300 875);
PAINT SKYBLUE (-5300 875);
FORCEPROP 1 LASTPIN (-5350 875) $PN 2
J 0
(-5340 855);
DISPLAY 0.617021 (-5340 855);
PAINT GREEN (-5340 855);
FORCEPROP 1 LASTPIN (-5350 1075) $PN 1
J 0
(-5340 1055);
DISPLAY 0.617021 (-5340 1055);
PAINT GREEN (-5340 1055);
FORCEPROP 1 LAST LOCATION C4U4
J 0
(-5300 1075);
DISPLAY 0.617021 (-5300 1075);
PAINT AQUA (-5300 1075);
FORCEPROP 1 LAST VALUE 10UF
J 0
(-5300 1025);
DISPLAY 0.617021 (-5300 1025);
PAINT SKYBLUE (-5300 1025);
FORCEPROP 1 LAST PART_NUMBER E15431-001
J 0
(-5300 825);
DISPLAY 0.617021 (-5300 825);
PAINT BLUE (-5300 825);
FORCEPROP 1 LAST VOLTAGE 4V
J 0
(-5300 975);
PAINT SKYBLUE (-5300 975);
DISPLAY INVISIBLE (-5300 975);
FORCEPROP 2 LAST CDS_LIB mstr_discrete
J 0
(-5350 975);
PAINT MONO (-5350 975);
DISPLAY INVISIBLE (-5350 975);
FORCEPROP 2 LAST CDS_LOCATION C4U4
J 0
(-5300 1075);
DISPLAY 0.617021 (-5300 1075);
PAINT AQUA (-5300 1075);
DISPLAY INVISIBLE (-5300 1075);
FORCEPROP 2 LAST ROOM PVPP_KLM_VR
J 0
(-5300 1125);
PAINT MONO (-5300 1125);
DISPLAY INVISIBLE (-5300 1125);
FORCEPROP 1 LAST PATH I146
J 0
(-5300 1125);
DISPLAY 0.978723 (-5300 1125);
PAINT WHITE (-5300 1125);
DISPLAY INVISIBLE (-5300 1125);
FORCEPROP 2 LAST BOM_COST MEM_VRD_PVPP_AB
J 0
(-5300 1125);
PAINT MONO (-5300 1125);
DISPLAY INVISIBLE (-5300 1125);
FORCEPROP 2 LAST $SEC 1
J 0
(-5300 1175);
PAINT MONO (-5300 1175);
DISPLAY INVISIBLE (-5300 1175);
FORCEPROP 2 LAST CDS_SEC 1
J 0
(-5300 1175);
PAINT MONO (-5300 1175);
DISPLAY INVISIBLE (-5300 1175);
FORCEADD GND..1
(-4900 675);
FORCEPROP 3 LASTPIN (-4900 725) SIG_NAME GND\g
J 0
(-4890 735);
DISPLAY 0.659574 (-4890 735);
PAINT MONO (-4890 735);
DISPLAY INVISIBLE (-4890 735);
FORCEPROP 2 LAST ROOM PVPP_KLM_VR
J 0
(-5450 750);
PAINT ORANGE (-5450 750);
DISPLAY INVISIBLE (-5450 750);
FORCEPROP 2 LAST BOM_COST MEM_VRD_PVPP_AB
J 0
(-5225 750);
PAINT MONO (-5225 750);
DISPLAY INVISIBLE (-5225 750);
FORCEPROP 1 LAST BODY_TYPE PLUMBING
J 0
(-4945 632);
DISPLAY 0.340426 (-4945 632);
PAINT GREEN (-4945 632);
DISPLAY INVISIBLE (-4945 632);
FORCEPROP 2 LAST CDS_LIB mstr_symbols
J 0
(-4900 675);
PAINT MONO (-4900 675);
DISPLAY INVISIBLE (-4900 675);
FORCEPROP 1 LAST VOLTAGE 0
J 0
(-4900 675);
PAINT SKYBLUE (-4900 675);
DISPLAY INVISIBLE (-4900 675);
FORCEPROP 1 LAST HDL_POWER GND
J 0
(-4900 825);
DISPLAY 0.893617 (-4900 825);
PAINT GREEN (-4900 825);
DISPLAY INVISIBLE (-4900 825);
FORCEPROP 1 LAST PATH I147
J 0
(-4825 675);
DISPLAY 0.872340 (-4825 675);
PAINT AQUA (-4825 675);
DISPLAY INVISIBLE (-4825 675);
FORCEPROP 1 LAST SIZE 1B
J 0
(-4825 625);
DISPLAY 0.893617 (-4825 625);
PAINT GREEN (-4825 625);
DISPLAY INVISIBLE (-4825 625);
FORCEADD CAP..1
(-5075 975);
FORCEPROP 1 LAST MATERIAL X6S
J 0
(-5025 875);
DISPLAY 0.617021 (-5025 875);
PAINT SKYBLUE (-5025 875);
FORCEPROP 1 LAST TOLERANCE 20%
J 0
(-5025 925);
DISPLAY 0.617021 (-5025 925);
PAINT SKYBLUE (-5025 925);
FORCEPROP 1 LASTPIN (-5075 875) $PN 2
J 0
(-5065 855);
DISPLAY 0.617021 (-5065 855);
PAINT GREEN (-5065 855);
FORCEPROP 1 LAST PACK_TYPE 0603LF
J 0
(-5025 775);
DISPLAY 0.617021 (-5025 775);
PAINT SKYBLUE (-5025 775);
FORCEPROP 1 LAST PART_NUMBER E15431-001
J 0
(-5025 825);
DISPLAY 0.617021 (-5025 825);
PAINT BLUE (-5025 825);
FORCEPROP 1 LASTPIN (-5075 1075) $PN 1
J 0
(-5065 1055);
DISPLAY 0.617021 (-5065 1055);
PAINT GREEN (-5065 1055);
FORCEPROP 1 LAST VALUE 10UF
J 0
(-5025 1025);
DISPLAY 0.617021 (-5025 1025);
PAINT SKYBLUE (-5025 1025);
FORCEPROP 1 LAST LOCATION C4U3
J 0
(-5025 1075);
DISPLAY 0.617021 (-5025 1075);
PAINT AQUA (-5025 1075);
FORCEPROP 1 LAST VOLTAGE 4V
J 0
(-5025 975);
PAINT SKYBLUE (-5025 975);
DISPLAY INVISIBLE (-5025 975);
FORCEPROP 2 LAST CDS_LIB mstr_discrete
J 0
(-5075 975);
PAINT MONO (-5075 975);
DISPLAY INVISIBLE (-5075 975);
FORCEPROP 2 LAST CDS_LOCATION C4U3
J 0
(-5025 1075);
DISPLAY 0.617021 (-5025 1075);
PAINT AQUA (-5025 1075);
DISPLAY INVISIBLE (-5025 1075);
FORCEPROP 2 LAST BOM_COST MEM_VRD_PVPP_AB
J 0
(-5025 1125);
PAINT MONO (-5025 1125);
DISPLAY INVISIBLE (-5025 1125);
FORCEPROP 1 LAST PATH I148
J 0
(-5025 1125);
DISPLAY 0.978723 (-5025 1125);
PAINT WHITE (-5025 1125);
DISPLAY INVISIBLE (-5025 1125);
FORCEPROP 2 LAST ROOM PVPP_KLM_VR
J 0
(-5025 1125);
PAINT MONO (-5025 1125);
DISPLAY INVISIBLE (-5025 1125);
FORCEPROP 2 LAST CDS_SEC 1
J 0
(-5025 1175);
PAINT MONO (-5025 1175);
DISPLAY INVISIBLE (-5025 1175);
FORCEPROP 2 LAST $SEC 1
J 0
(-5025 1175);
PAINT MONO (-5025 1175);
DISPLAY INVISIBLE (-5025 1175);
FORCEADD CAP..1
(-4825 1000);
FORCEPROP 1 LASTPIN (-4825 900) $PN 2
J 0
(-4815 880);
DISPLAY 0.617021 (-4815 880);
PAINT GREEN (-4815 880);
FORCEPROP 1 LAST MATERIAL X6S
J 0
(-4775 900);
DISPLAY 0.617021 (-4775 900);
PAINT SKYBLUE (-4775 900);
FORCEPROP 1 LAST TOLERANCE 20%
J 0
(-4775 950);
DISPLAY 0.617021 (-4775 950);
PAINT SKYBLUE (-4775 950);
FORCEPROP 1 LAST PACK_TYPE 0603LF
J 0
(-4775 800);
DISPLAY 0.617021 (-4775 800);
PAINT SKYBLUE (-4775 800);
FORCEPROP 1 LAST PART_NUMBER E15431-001
J 0
(-4775 850);
DISPLAY 0.617021 (-4775 850);
PAINT BLUE (-4775 850);
FORCEPROP 1 LASTPIN (-4825 1100) $PN 1
J 0
(-4815 1080);
DISPLAY 0.617021 (-4815 1080);
PAINT GREEN (-4815 1080);
FORCEPROP 1 LAST VALUE 10UF
J 0
(-4775 1050);
DISPLAY 0.617021 (-4775 1050);
PAINT SKYBLUE (-4775 1050);
FORCEPROP 1 LAST LOCATION C6F5
J 0
(-4775 1100);
DISPLAY 0.617021 (-4775 1100);
PAINT AQUA (-4775 1100);
FORCEPROP 2 LAST CDS_LIB mstr_discrete
J 0
(-4825 1000);
PAINT MONO (-4825 1000);
DISPLAY INVISIBLE (-4825 1000);
FORCEPROP 1 LAST VOLTAGE 4V
J 0
(-4775 1000);
PAINT SKYBLUE (-4775 1000);
DISPLAY INVISIBLE (-4775 1000);
FORCEPROP 2 LAST ROOM PVPP_KLM_VR
J 0
(-4775 1150);
PAINT MONO (-4775 1150);
DISPLAY INVISIBLE (-4775 1150);
FORCEPROP 1 LAST PATH I149
J 0
(-4775 1150);
DISPLAY 0.978723 (-4775 1150);
PAINT WHITE (-4775 1150);
DISPLAY INVISIBLE (-4775 1150);
FORCEPROP 2 LAST CDS_LOCATION C6F5
J 0
(-4775 1100);
DISPLAY 0.617021 (-4775 1100);
PAINT AQUA (-4775 1100);
DISPLAY INVISIBLE (-4775 1100);
FORCEPROP 2 LAST SEC 1
J 0
(-4755 1220);
DISPLAY 0.680851 (-4755 1220);
PAINT MONO (-4755 1220);
DISPLAY INVISIBLE (-4755 1220);
FORCEPROP 2 LAST SEC_TYPE 0603LF
J 0
(-4755 1220);
DISPLAY 1.021277 (-4755 1220);
PAINT ORANGE (-4755 1220);
DISPLAY INVISIBLE (-4755 1220);
FORCEPROP 2 LAST BOM_COST MEM_VRD_PVPP_AB
J 0
(-4775 1150);
PAINT MONO (-4775 1150);
DISPLAY INVISIBLE (-4775 1150);
FORCEADD CAP..1
(-6600 4375);
FORCEPROP 1 LASTPIN (-6600 4275) $PN 2
J 0
(-6590 4255);
DISPLAY 0.617021 (-6590 4255);
PAINT WHITE (-6590 4255);
FORCEPROP 1 LAST PACK_TYPE 1210
J 0
(-6550 4175);
DISPLAY 0.617021 (-6550 4175);
PAINT SKYBLUE (-6550 4175);
FORCEPROP 1 LAST TOLERANCE 20%
J 0
(-6550 4325);
DISPLAY 0.617021 (-6550 4325);
PAINT SKYBLUE (-6550 4325);
FORCEPROP 1 LAST MATERIAL X6S
J 0
(-6550 4275);
DISPLAY 0.617021 (-6550 4275);
PAINT SKYBLUE (-6550 4275);
FORCEPROP 1 LASTPIN (-6600 4475) $PN 1
J 0
(-6590 4455);
DISPLAY 0.617021 (-6590 4455);
PAINT WHITE (-6590 4455);
FORCEPROP 1 LAST LOCATION C7F7
J 0
(-6550 4475);
DISPLAY 0.617021 (-6550 4475);
PAINT AQUA (-6550 4475);
FORCEPROP 1 LAST VALUE 47UF
J 0
(-6550 4425);
DISPLAY 0.617021 (-6550 4425);
PAINT SKYBLUE (-6550 4425);
FORCEPROP 1 LAST VOLTAGE 16V
J 0
(-6550 4375);
DISPLAY 0.617021 (-6550 4375);
PAINT SKYBLUE (-6550 4375);
FORCEPROP 1 LAST PART_NUMBER D38464-007
J 0
(-6550 4225);
DISPLAY 0.617021 (-6550 4225);
PAINT BLUE (-6550 4225);
FORCEPROP 2 LAST ROOM PVPP_KLM_VR
J 0
(-6600 4375);
PAINT GREEN (-6600 4375);
DISPLAY INVISIBLE (-6600 4375);
FORCEPROP 2 LAST CDS_LIB mstr_discrete
J 0
(-6600 4375);
PAINT MONO (-6600 4375);
DISPLAY INVISIBLE (-6600 4375);
FORCEPROP 2 LAST BOM_COST PVPP_KLM_VR
J 0
(-6600 4375);
PAINT WHITE (-6600 4375);
DISPLAY INVISIBLE (-6600 4375);
FORCEPROP 2 LAST CDS_LOCATION C7F7
J 0
(-6550 4475);
DISPLAY 0.617021 (-6550 4475);
PAINT AQUA (-6550 4475);
DISPLAY INVISIBLE (-6550 4475);
FORCEPROP 1 LAST PATH I151
J 0
(-6550 4525);
DISPLAY 0.978723 (-6550 4525);
PAINT WHITE (-6550 4525);
DISPLAY INVISIBLE (-6550 4525);
FORCEPROP 2 LAST $SEC 1
J 0
(-6550 4575);
DISPLAY 0.680851 (-6550 4575);
PAINT MONO (-6550 4575);
DISPLAY INVISIBLE (-6550 4575);
FORCEPROP 2 LAST CDS_SEC 1
J 0
(-6550 4575);
DISPLAY 1.042553 (-6550 4575);
PAINT ORANGE (-6550 4575);
DISPLAY INVISIBLE (-6550 4575);
FORCEADD GND..1
(-6600 4200);
FORCEPROP 3 LASTPIN (-6600 4250) SIG_NAME GND\g
J 0
(-6590 4260);
DISPLAY 0.659574 (-6590 4260);
PAINT MONO (-6590 4260);
DISPLAY INVISIBLE (-6590 4260);
FORCEPROP 2 LAST ROOM PVPP_KLM_VR
J 0
(-7175 4275);
DISPLAY 1.042553 (-7175 4275);
PAINT GREEN (-7175 4275);
DISPLAY INVISIBLE (-7175 4275);
FORCEPROP 2 LAST BOM_COST PVPP_KLM_VR
J 0
(-7450 4275);
DISPLAY 1.042553 (-7450 4275);
PAINT WHITE (-7450 4275);
DISPLAY INVISIBLE (-7450 4275);
FORCEPROP 1 LAST VOLTAGE 0
J 0
(-6600 4200);
PAINT SKYBLUE (-6600 4200);
DISPLAY INVISIBLE (-6600 4200);
FORCEPROP 2 LAST CDS_LIB mstr_symbols
J 0
(-6600 4200);
PAINT MONO (-6600 4200);
DISPLAY INVISIBLE (-6600 4200);
FORCEPROP 1 LAST BODY_TYPE PLUMBING
J 0
(-6645 4157);
DISPLAY 0.340426 (-6645 4157);
PAINT GREEN (-6645 4157);
DISPLAY INVISIBLE (-6645 4157);
FORCEPROP 1 LAST SIZE 1B
J 0
(-6525 4150);
DISPLAY 0.872340 (-6525 4150);
PAINT GREEN (-6525 4150);
DISPLAY INVISIBLE (-6525 4150);
FORCEPROP 1 LAST PATH I152
J 0
(-6525 4200);
DISPLAY 0.872340 (-6525 4200);
PAINT AQUA (-6525 4200);
DISPLAY INVISIBLE (-6525 4200);
FORCEPROP 1 LAST HDL_POWER GND
J 0
(-6600 4350);
DISPLAY 0.872340 (-6600 4350);
PAINT GREEN (-6600 4350);
DISPLAY INVISIBLE (-6600 4350);
FORCEADD RES..1
(-3725 4450);
FORCEPROP 1 LAST WATTAGE 1/16W
J 2
(-3750 4275);
DISPLAY 0.617021 (-3750 4275);
PAINT SKYBLUE (-3750 4275);
FORCEPROP 1 LAST VALUE 0.0
J 2
(-3825 4325);
DISPLAY 0.617021 (-3825 4325);
PAINT SKYBLUE (-3825 4325);
FORCEPROP 1 LAST PART_NUMBER G21497-005
J 0
(-3875 4375);
DISPLAY 0.617021 (-3875 4375);
PAINT BLUE (-3875 4375);
FORCEPROP 1 LAST MATERIAL CHIP
J 0
(-3725 4275);
DISPLAY 0.617021 (-3725 4275);
PAINT SKYBLUE (-3725 4275);
FORCEPROP 1 LAST TOLERANCE 5%
J 0
(-3775 4325);
DISPLAY 0.617021 (-3775 4325);
PAINT SKYBLUE (-3775 4325);
FORCEPROP 1 LASTPIN (-3825 4450) $PN 1
J 0
(-3813 4462);
DISPLAY 0.617021 (-3813 4462);
PAINT WHITE (-3813 4462);
FORCEPROP 1 LAST LOCATION R7F8
J 0
(-3775 4500);
DISPLAY 0.617021 (-3775 4500);
PAINT AQUA (-3775 4500);
FORCEPROP 1 LASTPIN (-3625 4450) $PN 2
J 0
(-3663 4462);
DISPLAY 0.617021 (-3663 4462);
PAINT WHITE (-3663 4462);
FORCEPROP 1 LAST PACK_TYPE 0402
J 0
(-3675 4325);
DISPLAY 0.617021 (-3675 4325);
PAINT SKYBLUE (-3675 4325);
FORCEPROP 2 LAST ROOM PVPP_ABC_VR
J 0
(-3725 4450);
PAINT GREEN (-3725 4450);
DISPLAY INVISIBLE (-3725 4450);
FORCEPROP 2 LAST CDS_LOCATION R7F8
J 0
(-3775 4500);
DISPLAY 0.617021 (-3775 4500);
PAINT AQUA (-3775 4500);
DISPLAY INVISIBLE (-3775 4500);
FORCEPROP 2 LAST BOM_COST PVPP_ABC_VR
J 0
(-3725 4450);
PAINT WHITE (-3725 4450);
DISPLAY INVISIBLE (-3725 4450);
FORCEPROP 2 LAST CDS_LIB mstr_discrete
J 0
(-3725 4450);
PAINT MONO (-3725 4450);
DISPLAY INVISIBLE (-3725 4450);
FORCEPROP 1 LAST PATH I154
J 0
(-3775 4600);
DISPLAY 0.978723 (-3775 4600);
PAINT WHITE (-3775 4600);
DISPLAY INVISIBLE (-3775 4600);
FORCEPROP 0 LAST SPOF TRUE
J 0
(-3775 4600);
DISPLAY 1.021277 (-3775 4600);
PAINT ORANGE (-3775 4600);
DISPLAY INVISIBLE (-3775 4600);
FORCEPROP 2 LAST $SEC 1
J 0
(-3775 4650);
DISPLAY 0.680851 (-3775 4650);
PAINT MONO (-3775 4650);
DISPLAY INVISIBLE (-3775 4650);
FORCEPROP 2 LAST CDS_SEC 1
J 0
(-3775 4650);
DISPLAY 1.042553 (-3775 4650);
PAINT ORANGE (-3775 4650);
DISPLAY INVISIBLE (-3775 4650);
FORCEPROP 2 LAST REUSE_ID 13
J 0
(-3775 4650);
DISPLAY 1.042553 (-3775 4650);
PAINT ORANGE (-3775 4650);
DISPLAY INVISIBLE (-3775 4650);
FORCEADD CAP..2
R 2
(-3025 4450);
FORCEPROP 1 LASTPIN (-3125 4450) $PN 2
J 2
(-3110 4465);
DISPLAY 0.617021 (-3110 4465);
PAINT WHITE (-3110 4465);
FORCEPROP 1 LAST MATERIAL X7R
J 2
(-3025 4300);
DISPLAY 0.617021 (-3025 4300);
PAINT SKYBLUE (-3025 4300);
FORCEPROP 1 LAST VOLTAGE 25V
J 2
(-3025 4350);
DISPLAY 0.617021 (-3025 4350);
PAINT SKYBLUE (-3025 4350);
FORCEPROP 1 LAST PACK_TYPE 0603LF
J 1
(-3025 4250);
DISPLAY 0.617021 (-3025 4250);
PAINT SKYBLUE (-3025 4250);
FORCEPROP 1 LAST PART_NUMBER 602433-020
J 1
(-3025 4500);
DISPLAY 0.617021 (-3025 4500);
PAINT BLUE (-3025 4500);
FORCEPROP 1 LAST LOCATION C7F4
J 1
(-3025 4550);
DISPLAY 0.617021 (-3025 4550);
PAINT AQUA (-3025 4550);
FORCEPROP 1 LAST TOLERANCE 10%
J 0
(-3025 4300);
DISPLAY 0.617021 (-3025 4300);
PAINT SKYBLUE (-3025 4300);
FORCEPROP 1 LAST VALUE 0.1UF
J 0
(-3025 4350);
DISPLAY 0.617021 (-3025 4350);
PAINT SKYBLUE (-3025 4350);
FORCEPROP 1 LASTPIN (-2925 4450) $PN 1
J 2
(-2915 4465);
DISPLAY 0.617021 (-2915 4465);
PAINT WHITE (-2915 4465);
FORCEPROP 2 LAST CDS_LIB mstr_discrete
J 0
(-3025 4450);
PAINT MONO (-3025 4450);
DISPLAY INVISIBLE (-3025 4450);
FORCEPROP 2 LAST ROOM PVPP_KLM_VR
J 2
(-3025 4575);
DISPLAY 0.765957 (-3025 4575);
PAINT GREEN (-3025 4575);
DISPLAY INVISIBLE (-3025 4575);
FORCEPROP 2 LAST CDS_LOCATION C7F4
J 1
(-3025 4550);
DISPLAY 0.617021 (-3025 4550);
PAINT AQUA (-3025 4550);
DISPLAY INVISIBLE (-3025 4550);
FORCEPROP 2 LAST REUSE_ID 27
J 0
(-3025 4700);
DISPLAY 1.042553 (-3025 4700);
PAINT ORANGE (-3025 4700);
DISPLAY INVISIBLE (-3025 4700);
FORCEPROP 2 LAST CDS_SEC 1
J 0
(-3070 4660);
DISPLAY 1.042553 (-3070 4660);
PAINT ORANGE (-3070 4660);
DISPLAY INVISIBLE (-3070 4660);
FORCEPROP 0 LAST SPOF TRUE
J 0
(-3025 4650);
DISPLAY 1.021277 (-3025 4650);
PAINT ORANGE (-3025 4650);
DISPLAY INVISIBLE (-3025 4650);
FORCEPROP 2 LAST BOM_COST PVPP_KLM_VR
J 0
(-3070 4610);
DISPLAY 1.042553 (-3070 4610);
PAINT WHITE (-3070 4610);
DISPLAY INVISIBLE (-3070 4610);
FORCEPROP 2 LAST $SEC 1
J 0
(-3025 4700);
DISPLAY 0.680851 (-3025 4700);
PAINT MONO (-3025 4700);
DISPLAY INVISIBLE (-3025 4700);
FORCEPROP 1 LAST PATH I159
J 2
(-3025 4650);
DISPLAY 0.978723 (-3025 4650);
PAINT WHITE (-3025 4650);
DISPLAY INVISIBLE (-3025 4650);
FORCEADD GND..1
(-4600 4075);
FORCEPROP 3 LASTPIN (-4600 4125) SIG_NAME GND\g
J 0
(-4590 4135);
DISPLAY 0.659574 (-4590 4135);
PAINT MONO (-4590 4135);
DISPLAY INVISIBLE (-4590 4135);
FORCEPROP 1 LAST BODY_TYPE PLUMBING
J 0
(-4645 4032);
DISPLAY 0.340426 (-4645 4032);
PAINT GREEN (-4645 4032);
DISPLAY INVISIBLE (-4645 4032);
FORCEPROP 1 LAST SIZE 1B
J 0
(-4525 4025);
DISPLAY 0.872340 (-4525 4025);
PAINT GREEN (-4525 4025);
DISPLAY INVISIBLE (-4525 4025);
FORCEPROP 1 LAST PATH I160
J 0
(-4525 4075);
DISPLAY 0.872340 (-4525 4075);
PAINT AQUA (-4525 4075);
DISPLAY INVISIBLE (-4525 4075);
FORCEPROP 2 LAST CDS_LIB mstr_symbols
J 0
(-4600 4075);
PAINT MONO (-4600 4075);
DISPLAY INVISIBLE (-4600 4075);
FORCEPROP 1 LAST VOLTAGE 0
J 0
(-4600 4075);
PAINT SKYBLUE (-4600 4075);
DISPLAY INVISIBLE (-4600 4075);
FORCEPROP 2 LAST BOM_COST PVPP_KLM_VR
J 0
(-5450 4150);
DISPLAY 1.042553 (-5450 4150);
PAINT WHITE (-5450 4150);
DISPLAY INVISIBLE (-5450 4150);
FORCEPROP 2 LAST ROOM PVPP_KLM_VR
J 0
(-5175 4150);
DISPLAY 1.042553 (-5175 4150);
PAINT GREEN (-5175 4150);
DISPLAY INVISIBLE (-5175 4150);
FORCEPROP 1 LAST HDL_POWER GND
J 0
(-4600 4225);
DISPLAY 0.872340 (-4600 4225);
PAINT GREEN (-4600 4225);
DISPLAY INVISIBLE (-4600 4225);
FORCEADD CAP..1
(-4600 4400);
FORCEPROP 1 LASTPIN (-4600 4300) $PN 2
J 0
(-4590 4280);
DISPLAY 0.617021 (-4590 4280);
PAINT WHITE (-4590 4280);
FORCEPROP 1 LAST MATERIAL X6S
J 0
(-4550 4300);
DISPLAY 0.617021 (-4550 4300);
PAINT SKYBLUE (-4550 4300);
FORCEPROP 1 LAST PACK_TYPE 0402
J 0
(-4550 4200);
DISPLAY 0.617021 (-4550 4200);
PAINT SKYBLUE (-4550 4200);
FORCEPROP 1 LAST TOLERANCE 10%
J 0
(-4550 4350);
DISPLAY 0.617021 (-4550 4350);
PAINT SKYBLUE (-4550 4350);
FORCEPROP 1 LASTPIN (-4600 4500) $PN 1
J 0
(-4590 4480);
DISPLAY 0.617021 (-4590 4480);
PAINT WHITE (-4590 4480);
FORCEPROP 1 LAST VOLTAGE 16V
J 0
(-4550 4400);
DISPLAY 0.617021 (-4550 4400);
PAINT SKYBLUE (-4550 4400);
FORCEPROP 1 LAST VALUE 1.0UF
J 0
(-4550 4450);
DISPLAY 0.617021 (-4550 4450);
PAINT SKYBLUE (-4550 4450);
FORCEPROP 1 LAST LOCATION C3T10
J 0
(-4550 4500);
DISPLAY 0.617021 (-4550 4500);
PAINT AQUA (-4550 4500);
FORCEPROP 1 LAST PART_NUMBER D97712-011
J 0
(-4550 4250);
DISPLAY 0.617021 (-4550 4250);
PAINT BLUE (-4550 4250);
FORCEPROP 2 LAST CDS_LIB mstr_discrete
J 0
(-4600 4400);
PAINT MONO (-4600 4400);
DISPLAY INVISIBLE (-4600 4400);
FORCEPROP 2 LAST CDS_LOCATION C3T10
J 0
(-4550 4500);
DISPLAY 0.617021 (-4550 4500);
PAINT AQUA (-4550 4500);
DISPLAY INVISIBLE (-4550 4500);
FORCEPROP 1 LAST PATH I161
J 0
(-4550 4550);
DISPLAY 0.978723 (-4550 4550);
PAINT WHITE (-4550 4550);
DISPLAY INVISIBLE (-4550 4550);
FORCEPROP 2 LAST BOM_COST PVPP_KLM_VR
J 0
(-4600 4400);
PAINT WHITE (-4600 4400);
DISPLAY INVISIBLE (-4600 4400);
FORCEPROP 2 LAST ROOM PVPP_KLM_VR
J 0
(-4600 4400);
PAINT GREEN (-4600 4400);
DISPLAY INVISIBLE (-4600 4400);
FORCEPROP 0 LAST REUSE_ID 1
J 0
(-4550 4600);
DISPLAY 1.042553 (-4550 4600);
PAINT ORANGE (-4550 4600);
DISPLAY INVISIBLE (-4550 4600);
FORCEPROP 2 LAST CDS_SEC 1
J 0
(-4550 4600);
DISPLAY 1.042553 (-4550 4600);
PAINT ORANGE (-4550 4600);
DISPLAY INVISIBLE (-4550 4600);
FORCEPROP 2 LAST $SEC 1
J 0
(-4550 4600);
DISPLAY 0.680851 (-4550 4600);
PAINT MONO (-4550 4600);
DISPLAY INVISIBLE (-4550 4600);
FORCEPROP 0 LAST FIN VR_1P2
J 0
(-4550 4700);
PAINT ORANGE (-4550 4700);
DISPLAY INVISIBLE (-4550 4700);
FORCEADD FERRITE..1
(-6950 4550);
FORCEPROP 1 LASTPIN (-7050 4550) $PN 1
J 2
(-7015 4560);
DISPLAY 0.617021 (-7015 4560);
PAINT WHITE (-7015 4560);
FORCEPROP 1 LAST VALUE 22
J 2
(-6970 4450);
DISPLAY 0.617021 (-6970 4450);
PAINT SKYBLUE (-6970 4450);
FORCEPROP 1 LAST MATERIAL FB
J 0
(-6945 4450);
DISPLAY 0.617021 (-6945 4450);
PAINT SKYBLUE (-6945 4450);
FORCEPROP 1 LASTPIN (-6850 4550) $PN 2
J 0
(-6870 4560);
DISPLAY 0.617021 (-6870 4560);
PAINT WHITE (-6870 4560);
FORCEPROP 1 LAST PACK_TYPE SM
J 0
(-6870 4450);
DISPLAY 0.617021 (-6870 4450);
PAINT SKYBLUE (-6870 4450);
FORCEPROP 1 LAST LOCATION FB7F1
J 0
(-7045 4605);
DISPLAY 0.617021 (-7045 4605);
PAINT AQUA (-7045 4605);
FORCEPROP 1 LAST PART_NUMBER 656554-051
J 0
(-7045 4665);
DISPLAY 0.617021 (-7045 4665);
PAINT BLUE (-7045 4665);
FORCEPROP 2 LAST CDS_LIB mstr_discrete
J 0
(-6950 4550);
PAINT MONO (-6950 4550);
DISPLAY INVISIBLE (-6950 4550);
FORCEPROP 2 LAST CDS_LOCATION FB7F1
J 0
(-7045 4605);
DISPLAY 0.617021 (-7045 4605);
PAINT AQUA (-7045 4605);
DISPLAY INVISIBLE (-7045 4605);
FORCEPROP 2 LAST ROOM PVPP_KLM_VR
J 0
(-7025 4700);
DISPLAY 1.659574 (-7025 4700);
PAINT GREEN (-7025 4700);
DISPLAY INVISIBLE (-7025 4700);
FORCEPROP 1 LAST PATH I162
J 0
(-7045 4715);
DISPLAY 0.872340 (-7045 4715);
PAINT PURPLE (-7045 4715);
DISPLAY INVISIBLE (-7045 4715);
FORCEPROP 2 LAST SEC 1
J 0
(-7025 4775);
DISPLAY 1.106383 (-7025 4775);
PAINT MONO (-7025 4775);
DISPLAY INVISIBLE (-7025 4775);
FORCEPROP 0 LAST TOLERANCE 1%
J 0
(-7025 4700);
PAINT SKYBLUE (-7025 4700);
DISPLAY INVISIBLE (-7025 4700);
FORCEPROP 2 LAST SEC_TYPE SM
J 0
(-7025 4775);
DISPLAY 1.659574 (-7025 4775);
PAINT ORANGE (-7025 4775);
DISPLAY INVISIBLE (-7025 4775);
FORCEADD P12V_STBY..1
(-7200 4825);
FORCEPROP 3 LASTPIN (-7200 4775) SIG_NAME P12V_STBY\g
J 0
(-7190 4785);
DISPLAY 0.659574 (-7190 4785);
PAINT MONO (-7190 4785);
DISPLAY INVISIBLE (-7190 4785);
FORCEPROP 1 LAST HDL_POWER P12V_STBY
J 0
(-7500 4700);
DISPLAY 0.872340 (-7500 4700);
PAINT ORANGE (-7500 4700);
DISPLAY INVISIBLE (-7500 4700);
FORCEPROP 1 LAST BODY_TYPE PLUMBING
J 0
(-7245 4782);
DISPLAY 0.340426 (-7245 4782);
PAINT GREEN (-7245 4782);
DISPLAY INVISIBLE (-7245 4782);
FORCEPROP 2 LAST CDS_LIB mstr_symbols
J 0
(-7200 4825);
PAINT ORANGE (-7200 4825);
DISPLAY INVISIBLE (-7200 4825);
FORCEPROP 1 LAST VOLTAGE 12.0V
J 0
(-7245 4782);
DISPLAY 0.340426 (-7245 4782);
PAINT SKYBLUE (-7245 4782);
DISPLAY INVISIBLE (-7245 4782);
FORCEPROP 1 LAST SIZE 1B
J 0
(-7155 4847);
DISPLAY 0.340426 (-7155 4847);
PAINT GREEN (-7155 4847);
DISPLAY INVISIBLE (-7155 4847);
FORCEPROP 1 LAST PATH I163
J 0
(-7155 4827);
DISPLAY 0.340426 (-7155 4827);
PAINT GREEN (-7155 4827);
DISPLAY INVISIBLE (-7155 4827);
FORCEADD AGND_SCSI..1
(-1000 1425);
FORCEPROP 3 LASTPIN (-1000 1475) SIG_NAME AGND_PVPP_ABC\g
J 0
(-990 1485);
DISPLAY 0.659574 (-990 1485);
PAINT MONO (-990 1485);
DISPLAY INVISIBLE (-990 1485);
FORCEPROP 1 LAST HDL_POWER AGND_PVPP_ABC
J 1
(-925 1350);
DISPLAY 0.617021 (-925 1350);
PAINT GREEN (-925 1350);
FORCEPROP 2 LAST ROOM PVPP_KLM_VR
J 0
(-1150 1375);
DISPLAY 1.042553 (-1150 1375);
PAINT GREEN (-1150 1375);
DISPLAY INVISIBLE (-1150 1375);
FORCEPROP 1 LAST BODY_TYPE PLUMBING
J 0
(-1045 1382);
DISPLAY 0.340426 (-1045 1382);
PAINT GREEN (-1045 1382);
DISPLAY INVISIBLE (-1045 1382);
FORCEPROP 2 LAST BOM_COST PVPP_KLM_VR
J 0
(-1150 1375);
DISPLAY 1.042553 (-1150 1375);
PAINT WHITE (-1150 1375);
DISPLAY INVISIBLE (-1150 1375);
FORCEPROP 1 LAST VOLTAGE 0.0V
J 0
(-1045 1382);
DISPLAY 0.340426 (-1045 1382);
PAINT SKYBLUE (-1045 1382);
DISPLAY INVISIBLE (-1045 1382);
FORCEPROP 1 LAST PATH I165
J 0
(-925 1425);
DISPLAY 0.872340 (-925 1425);
PAINT AQUA (-925 1425);
DISPLAY INVISIBLE (-925 1425);
FORCEPROP 2 LAST CDS_LIB mstr_symbols
J 0
(-1000 1425);
PAINT MONO (-1000 1425);
DISPLAY INVISIBLE (-1000 1425);
FORCEADD RES..2
(-1000 1800);
FORCEPROP 1 LASTPIN (-1000 1700) $PN 2
J 0
(-995 1710);
DISPLAY 0.617021 (-995 1710);
PAINT WHITE (-995 1710);
FORCEPROP 1 LAST MATERIAL CHIP
J 0
(-960 1725);
DISPLAY 0.617021 (-960 1725);
PAINT SKYBLUE (-960 1725);
FORCEPROP 1 LAST PACK_TYPE 0402
J 0
(-960 1625);
DISPLAY 0.617021 (-960 1625);
PAINT SKYBLUE (-960 1625);
FORCEPROP 1 LAST WATTAGE 1/16W
J 0
(-960 1775);
DISPLAY 0.617021 (-960 1775);
PAINT SKYBLUE (-960 1775);
FORCEPROP 1 LASTPIN (-1000 1900) $PN 1
J 0
(-995 1862);
DISPLAY 0.617021 (-995 1862);
PAINT WHITE (-995 1862);
FORCEPROP 1 LAST TOLERANCE 1%
J 0
(-955 1825);
DISPLAY 0.617021 (-955 1825);
PAINT SKYBLUE (-955 1825);
FORCEPROP 1 LAST VALUE 6.34K
J 0
(-955 1875);
DISPLAY 0.617021 (-955 1875);
PAINT SKYBLUE (-955 1875);
FORCEPROP 1 LAST LOCATION R7F11
J 0
(-955 1925);
DISPLAY 0.617021 (-955 1925);
PAINT AQUA (-955 1925);
FORCEPROP 1 LAST PART_NUMBER G21796-146
J 0
(-960 1675);
DISPLAY 0.617021 (-960 1675);
PAINT BLUE (-960 1675);
FORCEPROP 2 LAST ROOM PVPP_KLM_VR
R 1
J 0
(-1200 1850);
DISPLAY 1.042553 (-1200 1850);
PAINT GREEN (-1200 1850);
DISPLAY INVISIBLE (-1200 1850);
FORCEPROP 2 LAST BOM_COST PVPP_KLM_VR
R 1
J 0
(-1300 1850);
DISPLAY 1.042553 (-1300 1850);
PAINT WHITE (-1300 1850);
DISPLAY INVISIBLE (-1300 1850);
FORCEPROP 2 LAST CDS_LIB mstr_discrete
R 1
J 0
(-1000 1800);
PAINT MONO (-1000 1800);
DISPLAY INVISIBLE (-1000 1800);
FORCEPROP 1 LAST PATH I166
J 0
(-950 1975);
DISPLAY 0.978723 (-950 1975);
PAINT WHITE (-950 1975);
DISPLAY INVISIBLE (-950 1975);
FORCEPROP 2 LAST CDS_LOCATION R7F11
J 0
(-955 1925);
DISPLAY 0.617021 (-955 1925);
PAINT AQUA (-955 1925);
DISPLAY INVISIBLE (-955 1925);
FORCEPROP 2 LAST $SEC 1
J 0
(-950 2025);
DISPLAY 0.680851 (-950 2025);
PAINT MONO (-950 2025);
DISPLAY INVISIBLE (-950 2025);
FORCEPROP 2 LAST CDS_SEC 1
J 0
(-950 2025);
DISPLAY 1.042553 (-950 2025);
PAINT ORANGE (-950 2025);
DISPLAY INVISIBLE (-950 2025);
FORCEPROP 2 LAST REUSE_ID 7
J 0
(-950 2025);
DISPLAY 1.042553 (-950 2025);
PAINT ORANGE (-950 2025);
DISPLAY INVISIBLE (-950 2025);
FORCEPROP 0 LAST SPOF TRUE
J 0
(-950 2025);
DISPLAY 1.021277 (-950 2025);
PAINT ORANGE (-950 2025);
DISPLAY INVISIBLE (-950 2025);
FORCEADD RES..2
(-1000 2425);
FORCEPROP 1 LAST MATERIAL CHIP
J 0
(-960 2300);
DISPLAY 0.617021 (-960 2300);
PAINT SKYBLUE (-960 2300);
FORCEPROP 1 LASTPIN (-1000 2325) $PN 2
J 0
(-995 2335);
DISPLAY 0.617021 (-995 2335);
PAINT WHITE (-995 2335);
FORCEPROP 1 LASTPIN (-1000 2525) $PN 1
J 0
(-995 2487);
DISPLAY 0.617021 (-995 2487);
PAINT WHITE (-995 2487);
FORCEPROP 1 LAST TOLERANCE 1%
J 0
(-955 2450);
DISPLAY 0.617021 (-955 2450);
PAINT SKYBLUE (-955 2450);
FORCEPROP 1 LAST WATTAGE 1/16W
J 0
(-960 2400);
DISPLAY 0.617021 (-960 2400);
PAINT SKYBLUE (-960 2400);
FORCEPROP 1 LAST PACK_TYPE 0402
J 0
(-960 2350);
DISPLAY 0.617021 (-960 2350);
PAINT SKYBLUE (-960 2350);
FORCEPROP 1 LAST VALUE 20.0K
J 0
(-955 2500);
DISPLAY 0.617021 (-955 2500);
PAINT SKYBLUE (-955 2500);
FORCEPROP 1 LAST PART_NUMBER G21796-040
J 0
(-985 2250);
DISPLAY 0.617021 (-985 2250);
PAINT BLUE (-985 2250);
FORCEPROP 1 LAST LOCATION R7F13
J 0
(-955 2550);
DISPLAY 0.617021 (-955 2550);
PAINT AQUA (-955 2550);
FORCEPROP 2 LAST CDS_LIB mstr_discrete
J 0
(-1000 2425);
PAINT MONO (-1000 2425);
DISPLAY INVISIBLE (-1000 2425);
FORCEPROP 2 LAST CDS_LOCATION R7F13
J 0
(-955 2550);
DISPLAY 0.617021 (-955 2550);
PAINT AQUA (-955 2550);
DISPLAY INVISIBLE (-955 2550);
FORCEPROP 2 LAST ROOM PVPP_KLM_VR
J 0
(-955 2580);
PAINT GREEN (-955 2580);
DISPLAY INVISIBLE (-955 2580);
FORCEPROP 1 LAST PATH I167
J 0
(-950 2600);
DISPLAY 0.978723 (-950 2600);
PAINT WHITE (-950 2600);
DISPLAY INVISIBLE (-950 2600);
FORCEPROP 2 LAST $SEC 1
J 0
(-950 2650);
DISPLAY 0.680851 (-950 2650);
PAINT MONO (-950 2650);
DISPLAY INVISIBLE (-950 2650);
FORCEPROP 2 LAST CDS_SEC 1
J 0
(-950 2650);
DISPLAY 1.042553 (-950 2650);
PAINT ORANGE (-950 2650);
DISPLAY INVISIBLE (-950 2650);
FORCEPROP 2 LAST BOM_COST PVPP_KLM_VR
J 0
(-955 2605);
DISPLAY 1.042553 (-955 2605);
PAINT WHITE (-955 2605);
DISPLAY INVISIBLE (-955 2605);
FORCEPROP 2 LAST REUSE_ID 9
J 0
(-950 2650);
DISPLAY 1.042553 (-950 2650);
PAINT ORANGE (-950 2650);
DISPLAY INVISIBLE (-950 2650);
FORCEPROP 0 LAST SPOF TRUE
J 0
(-950 2650);
DISPLAY 1.021277 (-950 2650);
PAINT ORANGE (-950 2650);
DISPLAY INVISIBLE (-950 2650);
FORCEADD RES..1
R 5
(-1000 3175);
FORCEPROP 1 LAST PACK_TYPE 0402
J 0
(-975 3025);
DISPLAY 0.617021 (-975 3025);
PAINT SKYBLUE (-975 3025);
FORCEPROP 1 LAST PART_NUMBER G21497-005
J 0
(-975 2975);
DISPLAY 0.617021 (-975 2975);
PAINT BLUE (-975 2975);
FORCEPROP 1 LASTPIN (-1000 3075) $PN 2
J 0
(-988 3113);
DISPLAY 0.617021 (-988 3113);
PAINT ORANGE (-988 3113);
FORCEPROP 1 LAST TOLERANCE 5%
J 0
(-975 3125);
DISPLAY 0.617021 (-975 3125);
PAINT SKYBLUE (-975 3125);
FORCEPROP 1 LASTPIN (-1000 3275) $PN 1
J 0
(-988 3263);
DISPLAY 0.617021 (-988 3263);
PAINT ORANGE (-988 3263);
FORCEPROP 1 LAST VALUE 0.0
J 0
(-950 3225);
DISPLAY 0.617021 (-950 3225);
PAINT SKYBLUE (-950 3225);
FORCEPROP 1 LAST MATERIAL CHIP
J 0
(-975 3075);
DISPLAY 0.617021 (-975 3075);
PAINT SKYBLUE (-975 3075);
FORCEPROP 1 LAST WATTAGE 1/16W
J 0
(-975 3175);
DISPLAY 0.617021 (-975 3175);
PAINT SKYBLUE (-975 3175);
FORCEPROP 1 LAST LOCATION R7F12
J 0
(-900 3125);
DISPLAY 0.617021 (-900 3125);
PAINT AQUA (-900 3125);
FORCEPROP 2 LAST CDS_LOCATION R7F12
J 0
(-900 3125);
DISPLAY 0.617021 (-900 3125);
PAINT AQUA (-900 3125);
DISPLAY INVISIBLE (-900 3125);
FORCEPROP 2 LAST CDS_LIB mstr_discrete
J 0
(-1000 3175);
PAINT ORANGE (-1000 3175);
DISPLAY INVISIBLE (-1000 3175);
FORCEPROP 1 LAST PATH I168
R 3
J 0
(-850 3225);
DISPLAY 0.978723 (-850 3225);
PAINT WHITE (-850 3225);
DISPLAY INVISIBLE (-850 3225);
FORCEPROP 2 LAST ROOM PVPP_KLM_VR
R 3
J 0
(-850 3225);
DISPLAY 1.659574 (-850 3225);
PAINT GREEN (-850 3225);
DISPLAY INVISIBLE (-850 3225);
FORCEPROP 2 LAST SEC_TYPE 0402
J 0
(-925 3325);
DISPLAY 1.021277 (-925 3325);
PAINT ORANGE (-925 3325);
DISPLAY INVISIBLE (-925 3325);
FORCEPROP 0 LAST SPOF TRUE
J 0
(-950 3325);
DISPLAY 1.021277 (-950 3325);
PAINT ORANGE (-950 3325);
DISPLAY INVISIBLE (-950 3325);
FORCEPROP 2 LAST SEC 1
J 0
(-925 3325);
DISPLAY 0.680851 (-925 3325);
PAINT MONO (-925 3325);
DISPLAY INVISIBLE (-925 3325);
FORCEADD GND..1
(-1250 625);
FORCEPROP 3 LASTPIN (-1250 675) SIG_NAME GND\g
J 0
(-1240 685);
DISPLAY 0.659574 (-1240 685);
PAINT MONO (-1240 685);
DISPLAY INVISIBLE (-1240 685);
FORCEPROP 2 LAST BOM_COST PVPP_KLM_VR
J 0
(-2100 700);
DISPLAY 1.042553 (-2100 700);
PAINT WHITE (-2100 700);
DISPLAY INVISIBLE (-2100 700);
FORCEPROP 2 LAST ROOM PVPP_KLM_VR
J 0
(-1825 700);
DISPLAY 1.042553 (-1825 700);
PAINT GREEN (-1825 700);
DISPLAY INVISIBLE (-1825 700);
FORCEPROP 1 LAST BODY_TYPE PLUMBING
J 0
(-1295 582);
DISPLAY 0.340426 (-1295 582);
PAINT GREEN (-1295 582);
DISPLAY INVISIBLE (-1295 582);
FORCEPROP 1 LAST PATH I169
J 0
(-1175 625);
DISPLAY 0.872340 (-1175 625);
PAINT AQUA (-1175 625);
DISPLAY INVISIBLE (-1175 625);
FORCEPROP 1 LAST VOLTAGE 0
J 0
(-1250 625);
PAINT SKYBLUE (-1250 625);
DISPLAY INVISIBLE (-1250 625);
FORCEPROP 1 LAST SIZE 1B
J 0
(-1175 575);
DISPLAY 0.872340 (-1175 575);
PAINT AQUA (-1175 575);
DISPLAY INVISIBLE (-1175 575);
FORCEPROP 2 LAST CDS_LIB mstr_symbols
J 0
(-1250 625);
PAINT MONO (-1250 625);
DISPLAY INVISIBLE (-1250 625);
FORCEPROP 1 LAST HDL_POWER GND
J 0
(-1250 775);
DISPLAY 0.872340 (-1250 775);
PAINT GREEN (-1250 775);
DISPLAY INVISIBLE (-1250 775);
FORCEADD RES..1
(-950 725);
FORCEPROP 1 LASTPIN (-1050 725) $PN 1
J 0
(-1038 737);
DISPLAY 0.617021 (-1038 737);
PAINT WHITE (-1038 737);
FORCEPROP 1 LAST WATTAGE 1/16W
J 2
(-950 575);
DISPLAY 0.617021 (-950 575);
PAINT SKYBLUE (-950 575);
FORCEPROP 1 LAST PACK_TYPE 0402
J 0
(-1025 525);
DISPLAY 0.617021 (-1025 525);
PAINT SKYBLUE (-1025 525);
FORCEPROP 1 LAST VALUE 0.0
J 2
(-975 625);
DISPLAY 0.617021 (-975 625);
PAINT SKYBLUE (-975 625);
FORCEPROP 1 LAST PART_NUMBER G21497-005
J 0
(-1075 675);
DISPLAY 0.617021 (-1075 675);
PAINT BLUE (-1075 675);
FORCEPROP 1 LAST TOLERANCE 5%
J 0
(-950 625);
DISPLAY 0.617021 (-950 625);
PAINT SKYBLUE (-950 625);
FORCEPROP 1 LAST MATERIAL CHIP
J 0
(-950 575);
DISPLAY 0.617021 (-950 575);
PAINT SKYBLUE (-950 575);
FORCEPROP 1 LASTPIN (-850 725) $PN 2
J 0
(-888 737);
DISPLAY 0.617021 (-888 737);
PAINT WHITE (-888 737);
FORCEPROP 1 LAST LOCATION R7F35
J 0
(-1000 775);
DISPLAY 0.617021 (-1000 775);
PAINT AQUA (-1000 775);
FORCEPROP 2 LAST CDS_LIB mstr_discrete
J 0
(-950 725);
PAINT MONO (-950 725);
DISPLAY INVISIBLE (-950 725);
FORCEPROP 2 LAST CDS_SEC 1
J 0
(-990 910);
PAINT MONO (-990 910);
DISPLAY INVISIBLE (-990 910);
FORCEPROP 2 LAST $SEC 1
J 0
(-985 930);
PAINT MONO (-985 930);
DISPLAY INVISIBLE (-985 930);
FORCEPROP 1 LAST PATH I170
J 0
(-1000 875);
DISPLAY 0.978723 (-1000 875);
PAINT WHITE (-1000 875);
DISPLAY INVISIBLE (-1000 875);
FORCEPROP 2 LAST ROOM PVPP_KLM_VR
J 0
(-1000 800);
PAINT GREEN (-1000 800);
DISPLAY INVISIBLE (-1000 800);
FORCEADD AGND_SCSI..1
(-700 625);
FORCEPROP 3 LASTPIN (-700 675) SIG_NAME AGND_PVPP_ABC\g
J 0
(-690 685);
DISPLAY 0.659574 (-690 685);
PAINT MONO (-690 685);
DISPLAY INVISIBLE (-690 685);
FORCEPROP 1 LAST HDL_POWER AGND_PVPP_ABC
J 1
(-625 550);
DISPLAY 0.617021 (-625 550);
PAINT GREEN (-625 550);
FORCEPROP 2 LAST ROOM PVPP_KLM_VR
J 0
(-850 575);
DISPLAY 1.042553 (-850 575);
PAINT GREEN (-850 575);
DISPLAY INVISIBLE (-850 575);
FORCEPROP 2 LAST BOM_COST PVPP_KLM_VR
J 0
(-850 575);
DISPLAY 1.042553 (-850 575);
PAINT WHITE (-850 575);
DISPLAY INVISIBLE (-850 575);
FORCEPROP 1 LAST PATH I171
J 0
(-625 625);
DISPLAY 0.872340 (-625 625);
PAINT AQUA (-625 625);
DISPLAY INVISIBLE (-625 625);
FORCEPROP 1 LAST BODY_TYPE PLUMBING
J 0
(-745 582);
DISPLAY 0.340426 (-745 582);
PAINT GREEN (-745 582);
DISPLAY INVISIBLE (-745 582);
FORCEPROP 2 LAST CDS_LIB mstr_symbols
J 0
(-700 625);
PAINT ORANGE (-700 625);
DISPLAY INVISIBLE (-700 625);
FORCEPROP 1 LAST VOLTAGE 0.0V
J 0
(-745 582);
DISPLAY 0.340426 (-745 582);
PAINT SKYBLUE (-745 582);
DISPLAY INVISIBLE (-745 582);
FORCEADD GND..1
(-2300 3400);
FORCEPROP 3 LASTPIN (-2300 3450) SIG_NAME GND\g
J 0
(-2290 3460);
DISPLAY 0.659574 (-2290 3460);
PAINT MONO (-2290 3460);
DISPLAY INVISIBLE (-2290 3460);
FORCEPROP 2 LAST BOM_COST PVPP_KLM_VR
J 0
(-3200 3550);
DISPLAY 1.042553 (-3200 3550);
PAINT WHITE (-3200 3550);
DISPLAY INVISIBLE (-3200 3550);
FORCEPROP 2 LAST ROOM PVPP_KLM_VR
J 0
(-2950 3550);
PAINT GREEN (-2950 3550);
DISPLAY INVISIBLE (-2950 3550);
FORCEPROP 1 LAST BODY_TYPE PLUMBING
J 0
(-2345 3357);
DISPLAY 0.340426 (-2345 3357);
PAINT GREEN (-2345 3357);
DISPLAY INVISIBLE (-2345 3357);
FORCEPROP 1 LAST PATH I173
J 0
(-2225 3400);
DISPLAY 0.872340 (-2225 3400);
PAINT AQUA (-2225 3400);
DISPLAY INVISIBLE (-2225 3400);
FORCEPROP 1 LAST SIZE 1B
J 0
(-2225 3425);
DISPLAY 0.893617 (-2225 3425);
PAINT GREEN (-2225 3425);
DISPLAY INVISIBLE (-2225 3425);
FORCEPROP 2 LAST CDS_LIB mstr_symbols
J 0
(-2300 3475);
PAINT MONO (-2300 3475);
DISPLAY INVISIBLE (-2300 3475);
FORCEPROP 1 LAST VOLTAGE 0
J 0
(-2300 3475);
PAINT SKYBLUE (-2300 3475);
DISPLAY INVISIBLE (-2300 3475);
FORCEPROP 1 LAST HDL_POWER GND
J 0
(-2300 3625);
DISPLAY 0.893617 (-2300 3625);
PAINT GREEN (-2300 3625);
DISPLAY INVISIBLE (-2300 3625);
FORCEADD RES..2
(-2300 3600);
FORCEPROP 1 LASTPIN (-2300 3500) $PN 2
J 0
(-2295 3510);
DISPLAY 0.617021 (-2295 3510);
PAINT WHITE (-2295 3510);
FORCEPROP 1 LAST PACK_TYPE 0402
J 0
(-2185 3475);
DISPLAY 0.617021 (-2185 3475);
PAINT SKYBLUE (-2185 3475);
FORCEPROP 1 LASTPIN (-2300 3700) $PN 1
J 0
(-2295 3662);
DISPLAY 0.617021 (-2295 3662);
PAINT WHITE (-2295 3662);
FORCEPROP 1 LAST TOLERANCE 5%
J 0
(-2180 3625);
DISPLAY 0.617021 (-2180 3625);
PAINT SKYBLUE (-2180 3625);
FORCEPROP 1 LAST VALUE 2.2
J 0
(-2180 3675);
DISPLAY 0.617021 (-2180 3675);
PAINT SKYBLUE (-2180 3675);
FORCEPROP 1 LAST LOCATION R7F7
J 0
(-2255 3700);
DISPLAY 0.617021 (-2255 3700);
PAINT AQUA (-2255 3700);
FORCEPROP 1 LAST WATTAGE 1/16W
J 0
(-2185 3525);
DISPLAY 0.617021 (-2185 3525);
PAINT SKYBLUE (-2185 3525);
FORCEPROP 1 LAST PART_NUMBER G21497-016
J 0
(-2185 3425);
DISPLAY 0.617021 (-2185 3425);
PAINT BLUE (-2185 3425);
FORCEPROP 1 LAST MATERIAL EMPTY
J 0
(-2185 3575);
DISPLAY 0.617021 (-2185 3575);
PAINT RED (-2185 3575);
FORCEPROP 2 LAST CDS_LIB mstr_discrete
J 0
(-2300 3600);
PAINT MONO (-2300 3600);
DISPLAY INVISIBLE (-2300 3600);
FORCEPROP 2 LAST CDS_LOCATION R7F7
J 0
(-2255 3700);
DISPLAY 0.617021 (-2255 3700);
PAINT AQUA (-2255 3700);
DISPLAY INVISIBLE (-2255 3700);
FORCEPROP 2 LAST ROOM PVPP_KLM_VR
J 0
(-2250 3750);
PAINT GREEN (-2250 3750);
DISPLAY INVISIBLE (-2250 3750);
FORCEPROP 1 LAST PATH I174
J 0
(-2250 3775);
DISPLAY 0.978723 (-2250 3775);
PAINT WHITE (-2250 3775);
DISPLAY INVISIBLE (-2250 3775);
FORCEPROP 2 LAST BOM_COST PVPP_KLM_VR
J 0
(-2250 3775);
DISPLAY 1.042553 (-2250 3775);
PAINT WHITE (-2250 3775);
DISPLAY INVISIBLE (-2250 3775);
FORCEPROP 2 LAST $SEC 1
J 0
(-2250 3825);
DISPLAY 0.680851 (-2250 3825);
PAINT MONO (-2250 3825);
DISPLAY INVISIBLE (-2250 3825);
FORCEPROP 2 LAST CDS_SEC 1
J 0
(-2250 3825);
DISPLAY 1.042553 (-2250 3825);
PAINT ORANGE (-2250 3825);
DISPLAY INVISIBLE (-2250 3825);
FORCEPROP 2 LAST REUSE_ID 29
J 0
(-2250 3825);
DISPLAY 1.042553 (-2250 3825);
PAINT ORANGE (-2250 3825);
DISPLAY INVISIBLE (-2250 3825);
FORCEADD CAP..1
(-2300 3950);
FORCEPROP 1 LASTPIN (-2300 3850) $PN 2
J 0
(-2290 3830);
DISPLAY 0.617021 (-2290 3830);
PAINT WHITE (-2290 3830);
FORCEPROP 1 LASTPIN (-2300 4050) $PN 1
J 0
(-2290 4030);
DISPLAY 0.617021 (-2290 4030);
PAINT WHITE (-2290 4030);
FORCEPROP 1 LAST LOCATION C7F3
J 0
(-2200 4050);
DISPLAY 0.617021 (-2200 4050);
PAINT AQUA (-2200 4050);
FORCEPROP 1 LAST VOLTAGE 50V
J 0
(-2175 3950);
DISPLAY 0.617021 (-2175 3950);
PAINT SKYBLUE (-2175 3950);
FORCEPROP 1 LAST TOLERANCE 10%
J 0
(-2175 3900);
DISPLAY 0.617021 (-2175 3900);
PAINT SKYBLUE (-2175 3900);
FORCEPROP 1 LAST PACK_TYPE 0402LF
J 0
(-2175 3850);
DISPLAY 0.617021 (-2175 3850);
PAINT SKYBLUE (-2175 3850);
FORCEPROP 1 LAST VALUE 3300PF
J 0
(-2175 4000);
DISPLAY 0.617021 (-2175 4000);
PAINT SKYBLUE (-2175 4000);
FORCEPROP 1 LAST PART_NUMBER A36096-091
J 0
(-2175 3800);
DISPLAY 0.617021 (-2175 3800);
PAINT BLUE (-2175 3800);
FORCEPROP 1 LAST MATERIAL EMPTY
J 0
(-2075 3925);
DISPLAY 0.617021 (-2075 3925);
PAINT RED (-2075 3925);
FORCEPROP 2 LAST CDS_LIB mstr_discrete
J 0
(-2300 3950);
PAINT MONO (-2300 3950);
DISPLAY INVISIBLE (-2300 3950);
FORCEPROP 2 LAST CDS_LOCATION C7F3
J 0
(-2200 4050);
DISPLAY 0.617021 (-2200 4050);
PAINT AQUA (-2200 4050);
DISPLAY INVISIBLE (-2200 4050);
FORCEPROP 2 LAST ROOM PVPP_KLM_VR
J 0
(-2250 4075);
PAINT GREEN (-2250 4075);
DISPLAY INVISIBLE (-2250 4075);
FORCEPROP 1 LAST PATH I175
J 0
(-2250 4100);
DISPLAY 0.978723 (-2250 4100);
PAINT WHITE (-2250 4100);
DISPLAY INVISIBLE (-2250 4100);
FORCEPROP 2 LAST $SEC 1
J 0
(-2250 4150);
DISPLAY 0.680851 (-2250 4150);
PAINT MONO (-2250 4150);
DISPLAY INVISIBLE (-2250 4150);
FORCEPROP 2 LAST CDS_SEC 1
J 0
(-2250 4150);
DISPLAY 1.042553 (-2250 4150);
PAINT ORANGE (-2250 4150);
DISPLAY INVISIBLE (-2250 4150);
FORCEPROP 2 LAST REUSE_ID 26
J 0
(-2250 4150);
DISPLAY 1.042553 (-2250 4150);
PAINT ORANGE (-2250 4150);
DISPLAY INVISIBLE (-2250 4150);
FORCEPROP 2 LAST BOM_COST PVPP_KLM_VR
J 0
(-2250 4100);
DISPLAY 1.042553 (-2250 4100);
PAINT WHITE (-2250 4100);
DISPLAY INVISIBLE (-2250 4100);
FORCEADD GND..1
(-1725 3675);
FORCEPROP 3 LASTPIN (-1725 3725) SIG_NAME GND\g
J 0
(-1715 3735);
DISPLAY 0.659574 (-1715 3735);
PAINT MONO (-1715 3735);
DISPLAY INVISIBLE (-1715 3735);
FORCEPROP 2 LAST BOM_COST PVPP_KLM_VR
J 0
(-2575 3750);
DISPLAY 1.042553 (-2575 3750);
PAINT WHITE (-2575 3750);
DISPLAY INVISIBLE (-2575 3750);
FORCEPROP 2 LAST ROOM PVPP_KLM_VR
J 0
(-2300 3750);
DISPLAY 1.042553 (-2300 3750);
PAINT GREEN (-2300 3750);
DISPLAY INVISIBLE (-2300 3750);
FORCEPROP 1 LAST VOLTAGE 0
J 0
(-1725 3675);
PAINT SKYBLUE (-1725 3675);
DISPLAY INVISIBLE (-1725 3675);
FORCEPROP 2 LAST CDS_LIB mstr_symbols
J 0
(-1725 3675);
PAINT MONO (-1725 3675);
DISPLAY INVISIBLE (-1725 3675);
FORCEPROP 1 LAST BODY_TYPE PLUMBING
J 0
(-1770 3632);
DISPLAY 0.340426 (-1770 3632);
PAINT GREEN (-1770 3632);
DISPLAY INVISIBLE (-1770 3632);
FORCEPROP 1 LAST SIZE 1B
J 0
(-1650 3625);
DISPLAY 0.872340 (-1650 3625);
PAINT GREEN (-1650 3625);
DISPLAY INVISIBLE (-1650 3625);
FORCEPROP 1 LAST PATH I176
J 0
(-1650 3675);
DISPLAY 0.872340 (-1650 3675);
PAINT AQUA (-1650 3675);
DISPLAY INVISIBLE (-1650 3675);
FORCEPROP 1 LAST HDL_POWER GND
J 0
(-1725 3825);
DISPLAY 0.872340 (-1725 3825);
PAINT GREEN (-1725 3825);
DISPLAY INVISIBLE (-1725 3825);
FORCEADD RES..2
(-1725 3925);
FORCEPROP 1 LAST PACK_TYPE 0603
J 0
(-1685 3750);
DISPLAY 0.617021 (-1685 3750);
PAINT SKYBLUE (-1685 3750);
FORCEPROP 1 LASTPIN (-1725 3825) $PN 2
J 0
(-1720 3835);
DISPLAY 0.617021 (-1720 3835);
PAINT WHITE (-1720 3835);
FORCEPROP 1 LASTPIN (-1725 4025) $PN 1
J 0
(-1720 3987);
DISPLAY 0.617021 (-1720 3987);
PAINT WHITE (-1720 3987);
FORCEPROP 1 LAST TOLERANCE 1%
J 0
(-1680 3950);
DISPLAY 0.617021 (-1680 3950);
PAINT SKYBLUE (-1680 3950);
FORCEPROP 1 LAST MATERIAL CHIP
J 0
(-1685 3850);
DISPLAY 0.617021 (-1685 3850);
PAINT SKYBLUE (-1685 3850);
FORCEPROP 1 LAST WATTAGE 1/10W
J 0
(-1685 3900);
DISPLAY 0.617021 (-1685 3900);
PAINT SKYBLUE (-1685 3900);
FORCEPROP 1 LAST VALUE 120.0
J 0
(-1680 4000);
DISPLAY 0.617021 (-1680 4000);
PAINT SKYBLUE (-1680 4000);
FORCEPROP 1 LAST PART_NUMBER G22026-003
J 0
(-1685 3800);
DISPLAY 0.617021 (-1685 3800);
PAINT BLUE (-1685 3800);
FORCEPROP 1 LAST LOCATION R7F10
J 0
(-1680 4050);
DISPLAY 0.617021 (-1680 4050);
PAINT AQUA (-1680 4050);
FORCEPROP 2 LAST CDS_LIB mstr_discrete
J 0
(-1725 3925);
PAINT MONO (-1725 3925);
DISPLAY INVISIBLE (-1725 3925);
FORCEPROP 2 LAST CDS_LOCATION R7F10
J 0
(-1680 4050);
DISPLAY 0.617021 (-1680 4050);
PAINT AQUA (-1680 4050);
DISPLAY INVISIBLE (-1680 4050);
FORCEPROP 2 LAST ROOM PVPP_KLM_VR
J 0
(-1680 4080);
PAINT GREEN (-1680 4080);
DISPLAY INVISIBLE (-1680 4080);
FORCEPROP 1 LAST PATH I177
J 0
(-1675 4100);
DISPLAY 0.978723 (-1675 4100);
PAINT WHITE (-1675 4100);
DISPLAY INVISIBLE (-1675 4100);
FORCEPROP 2 LAST SEC 1
J 0
(-1675 4150);
DISPLAY 0.680851 (-1675 4150);
PAINT MONO (-1675 4150);
DISPLAY INVISIBLE (-1675 4150);
FORCEPROP 2 LAST REUSE_ID 34
J 0
(-1675 4150);
DISPLAY 1.042553 (-1675 4150);
PAINT ORANGE (-1675 4150);
DISPLAY INVISIBLE (-1675 4150);
FORCEPROP 2 LAST BOM_COST PVPP_KLM_VR
J 0
(-1680 4105);
DISPLAY 1.042553 (-1680 4105);
PAINT WHITE (-1680 4105);
DISPLAY INVISIBLE (-1680 4105);
FORCEPROP 2 LAST SEC_TYPE 0603
J 0
(-1675 4150);
DISPLAY 1.021277 (-1675 4150);
PAINT ORANGE (-1675 4150);
DISPLAY INVISIBLE (-1675 4150);
FORCEADD INDUCTOR..1
(-1950 4100);
FORCEPROP 1 LAST MATERIAL IND
J 0
(-1985 4040);
DISPLAY 0.617021 (-1985 4040);
PAINT SKYBLUE (-1985 4040);
FORCEPROP 1 LAST VALUE 0.47UH
J 2
(-2080 4115);
DISPLAY 0.617021 (-2080 4115);
PAINT SKYBLUE (-2080 4115);
FORCEPROP 1 LASTPIN (-2050 4100) $PN 1
J 0
(-2050 4110);
DISPLAY 0.617021 (-2050 4110);
PAINT WHITE (-2050 4110);
FORCEPROP 1 LAST PART_NUMBER E13358-018
J 0
(-2050 4200);
DISPLAY 0.617021 (-2050 4200);
PAINT BLUE (-2050 4200);
FORCEPROP 1 LAST LOCATION L7F1
J 0
(-2000 4150);
DISPLAY 0.617021 (-2000 4150);
PAINT AQUA (-2000 4150);
FORCEPROP 1 LASTPIN (-1850 4100) $PN 2
J 2
(-1840 4110);
DISPLAY 0.617021 (-1840 4110);
PAINT WHITE (-1840 4110);
FORCEPROP 1 LAST PACK_TYPE SM
J 0
(-1810 4115);
DISPLAY 0.617021 (-1810 4115);
PAINT SKYBLUE (-1810 4115);
FORCEPROP 1 LAST PATH I178
J 0
(-2050 4250);
DISPLAY 0.978723 (-2050 4250);
PAINT ORANGE (-2050 4250);
DISPLAY INVISIBLE (-2050 4250);
FORCEPROP 0 LAST TOLERANCE 1%
J 0
(-2050 4250);
PAINT SKYBLUE (-2050 4250);
DISPLAY INVISIBLE (-2050 4250);
FORCEPROP 2 LAST $SEC 1
J 0
(-2050 4300);
DISPLAY 0.680851 (-2050 4300);
PAINT MONO (-2050 4300);
DISPLAY INVISIBLE (-2050 4300);
FORCEPROP 2 LAST CDS_SEC 1
J 0
(-2050 4300);
DISPLAY 1.042553 (-2050 4300);
PAINT ORANGE (-2050 4300);
DISPLAY INVISIBLE (-2050 4300);
FORCEPROP 2 LAST REUSE_ID 30
J 0
(-2050 4300);
DISPLAY 1.042553 (-2050 4300);
PAINT ORANGE (-2050 4300);
DISPLAY INVISIBLE (-2050 4300);
FORCEPROP 2 LAST CDS_LIB mstr_discrete
J 0
(-1950 4100);
PAINT MONO (-1950 4100);
DISPLAY INVISIBLE (-1950 4100);
FORCEPROP 2 LAST BOM_COST PVPP_KLM_VR
J 0
(-1950 4100);
PAINT WHITE (-1950 4100);
DISPLAY INVISIBLE (-1950 4100);
FORCEPROP 2 LAST CDS_LOCATION L7F1
J 0
(-2000 4150);
DISPLAY 0.617021 (-2000 4150);
PAINT AQUA (-2000 4150);
DISPLAY INVISIBLE (-2000 4150);
FORCEPROP 2 LAST ROOM PVPP_KLM_VR
J 2
(-1950 4100);
PAINT GREEN (-1950 4100);
DISPLAY INVISIBLE (-1950 4100);
FORCEADD GND..1
(-1400 3625);
FORCEPROP 3 LASTPIN (-1400 3675) SIG_NAME GND\g
J 0
(-1390 3685);
DISPLAY 0.659574 (-1390 3685);
PAINT MONO (-1390 3685);
DISPLAY INVISIBLE (-1390 3685);
FORCEPROP 2 LAST BOM_COST PVPP_KLM_VR
J 0
(-2250 3700);
DISPLAY 1.042553 (-2250 3700);
PAINT WHITE (-2250 3700);
DISPLAY INVISIBLE (-2250 3700);
FORCEPROP 2 LAST ROOM PVPP_KLM_VR
J 0
(-1975 3700);
DISPLAY 1.042553 (-1975 3700);
PAINT GREEN (-1975 3700);
DISPLAY INVISIBLE (-1975 3700);
FORCEPROP 1 LAST BODY_TYPE PLUMBING
J 0
(-1445 3582);
DISPLAY 0.340426 (-1445 3582);
PAINT GREEN (-1445 3582);
DISPLAY INVISIBLE (-1445 3582);
FORCEPROP 1 LAST SIZE 1B
J 0
(-1325 3575);
DISPLAY 0.872340 (-1325 3575);
PAINT GREEN (-1325 3575);
DISPLAY INVISIBLE (-1325 3575);
FORCEPROP 1 LAST PATH I179
J 0
(-1325 3625);
DISPLAY 0.872340 (-1325 3625);
PAINT AQUA (-1325 3625);
DISPLAY INVISIBLE (-1325 3625);
FORCEPROP 2 LAST CDS_LIB mstr_symbols
J 0
(-1400 3625);
PAINT MONO (-1400 3625);
DISPLAY INVISIBLE (-1400 3625);
FORCEPROP 1 LAST VOLTAGE 0
J 0
(-1400 3625);
PAINT SKYBLUE (-1400 3625);
DISPLAY INVISIBLE (-1400 3625);
FORCEPROP 1 LAST HDL_POWER GND
J 0
(-1400 3775);
DISPLAY 0.872340 (-1400 3775);
PAINT GREEN (-1400 3775);
DISPLAY INVISIBLE (-1400 3775);
FORCEADD CAPP..1
(-1400 3925);
FORCEPROP 1 LASTPIN (-1400 3825) $PN 2
J 0
(-1390 3810);
DISPLAY 0.617021 (-1390 3810);
PAINT WHITE (-1390 3810);
FORCEPROP 1 LASTPIN (-1400 4025) $PN 1
J 0
(-1390 4010);
DISPLAY 0.617021 (-1390 4010);
PAINT WHITE (-1390 4010);
FORCEPROP 1 LAST MATERIAL POSCAP
J 0
(-1350 3825);
DISPLAY 0.617021 (-1350 3825);
PAINT SKYBLUE (-1350 3825);
FORCEPROP 1 LAST VOLTAGE 6.3V
J 0
(-1350 3875);
DISPLAY 0.617021 (-1350 3875);
PAINT SKYBLUE (-1350 3875);
FORCEPROP 1 LAST PACK_TYPE 7343LF
J 0
(-1350 3775);
DISPLAY 0.617021 (-1350 3775);
PAINT SKYBLUE (-1350 3775);
FORCEPROP 1 LAST TOLERANCE 20%
J 0
(-1350 3925);
DISPLAY 0.617021 (-1350 3925);
PAINT SKYBLUE (-1350 3925);
FORCEPROP 1 LAST VALUE 330UF
J 0
(-1350 3975);
DISPLAY 0.617021 (-1350 3975);
PAINT SKYBLUE (-1350 3975);
FORCEPROP 1 LAST PART_NUMBER 724613-042
J 0
(-1350 3725);
DISPLAY 0.617021 (-1350 3725);
PAINT BLUE (-1350 3725);
FORCEPROP 1 LAST LOCATION C6F4
J 0
(-1350 4025);
DISPLAY 0.617021 (-1350 4025);
PAINT AQUA (-1350 4025);
FORCEPROP 2 LAST CDS_LIB mstr_discrete
J 0
(-1400 3925);
PAINT MONO (-1400 3925);
DISPLAY INVISIBLE (-1400 3925);
FORCEPROP 2 LAST BOM_COST PVPP_KLM_VR
J 0
(-1400 3925);
DISPLAY 0.659574 (-1400 3925);
PAINT WHITE (-1400 3925);
DISPLAY INVISIBLE (-1400 3925);
FORCEPROP 2 LAST ROOM PVPP_KLM_VR
J 0
(-1400 3925);
PAINT GREEN (-1400 3925);
DISPLAY INVISIBLE (-1400 3925);
FORCEPROP 2 LAST CDS_LOCATION C6F4
J 0
(-1350 4025);
DISPLAY 0.617021 (-1350 4025);
PAINT AQUA (-1350 4025);
DISPLAY INVISIBLE (-1350 4025);
FORCEPROP 1 LAST PATH I180
J 0
(-1350 4075);
DISPLAY 0.978723 (-1350 4075);
PAINT ORANGE (-1350 4075);
DISPLAY INVISIBLE (-1350 4075);
FORCEPROP 2 LAST $SEC 1
J 0
(-1350 4125);
DISPLAY 0.680851 (-1350 4125);
PAINT MONO (-1350 4125);
DISPLAY INVISIBLE (-1350 4125);
FORCEPROP 2 LAST CDS_SEC 1
J 0
(-1350 4125);
DISPLAY 1.042553 (-1350 4125);
PAINT ORANGE (-1350 4125);
DISPLAY INVISIBLE (-1350 4125);
FORCEPROP 2 LAST REUSE_ID 28
J 0
(-1350 4125);
DISPLAY 1.042553 (-1350 4125);
PAINT ORANGE (-1350 4125);
DISPLAY INVISIBLE (-1350 4125);
FORCEADD GND..1
(-825 3650);
FORCEPROP 3 LASTPIN (-825 3700) SIG_NAME GND\g
J 0
(-815 3710);
DISPLAY 0.659574 (-815 3710);
PAINT MONO (-815 3710);
DISPLAY INVISIBLE (-815 3710);
FORCEPROP 2 LAST BOM_COST PVPP_KLM_VR
J 0
(-1675 3725);
DISPLAY 1.042553 (-1675 3725);
PAINT WHITE (-1675 3725);
DISPLAY INVISIBLE (-1675 3725);
FORCEPROP 2 LAST ROOM PVPP_KLM_VR
J 0
(-1400 3725);
DISPLAY 1.042553 (-1400 3725);
PAINT GREEN (-1400 3725);
DISPLAY INVISIBLE (-1400 3725);
FORCEPROP 1 LAST BODY_TYPE PLUMBING
J 0
(-870 3607);
DISPLAY 0.340426 (-870 3607);
PAINT GREEN (-870 3607);
DISPLAY INVISIBLE (-870 3607);
FORCEPROP 2 LAST CDS_LIB mstr_symbols
J 0
(-825 3650);
PAINT MONO (-825 3650);
DISPLAY INVISIBLE (-825 3650);
FORCEPROP 1 LAST VOLTAGE 0
J 0
(-825 3650);
PAINT SKYBLUE (-825 3650);
DISPLAY INVISIBLE (-825 3650);
FORCEPROP 1 LAST HDL_POWER GND
J 0
(-825 3800);
DISPLAY 0.872340 (-825 3800);
PAINT GREEN (-825 3800);
DISPLAY INVISIBLE (-825 3800);
FORCEPROP 1 LAST PATH I183
J 0
(-750 3650);
DISPLAY 0.872340 (-750 3650);
PAINT AQUA (-750 3650);
DISPLAY INVISIBLE (-750 3650);
FORCEPROP 1 LAST SIZE 1B
J 0
(-750 3600);
DISPLAY 0.872340 (-750 3600);
PAINT GREEN (-750 3600);
DISPLAY INVISIBLE (-750 3600);
FORCEADD CAP..1
(-825 3925);
FORCEPROP 1 LASTPIN (-825 3825) $PN 2
J 0
(-815 3805);
DISPLAY 0.617021 (-815 3805);
PAINT WHITE (-815 3805);
FORCEPROP 1 LASTPIN (-825 4025) $PN 1
J 0
(-815 4005);
DISPLAY 0.617021 (-815 4005);
PAINT WHITE (-815 4005);
FORCEPROP 1 LAST MATERIAL X6S
J 0
(-775 3825);
DISPLAY 0.617021 (-775 3825);
PAINT SKYBLUE (-775 3825);
FORCEPROP 1 LAST VOLTAGE 4V
J 0
(-775 3925);
DISPLAY 0.617021 (-775 3925);
PAINT SKYBLUE (-775 3925);
FORCEPROP 1 LAST PACK_TYPE 0805
J 0
(-775 3725);
DISPLAY 0.617021 (-775 3725);
PAINT SKYBLUE (-775 3725);
FORCEPROP 1 LAST TOLERANCE 20%
J 0
(-775 3875);
DISPLAY 0.617021 (-775 3875);
PAINT SKYBLUE (-775 3875);
FORCEPROP 1 LAST VALUE 47UF
J 0
(-775 3975);
DISPLAY 0.617021 (-775 3975);
PAINT SKYBLUE (-775 3975);
FORCEPROP 1 LAST LOCATION C3T7
J 0
(-775 4025);
DISPLAY 0.617021 (-775 4025);
PAINT AQUA (-775 4025);
FORCEPROP 1 LAST PART_NUMBER C95333-006
J 0
(-775 3775);
DISPLAY 0.617021 (-775 3775);
PAINT BLUE (-775 3775);
FORCEPROP 2 LAST ROOM PVPP_KLM_VR
J 0
(-825 3925);
PAINT GREEN (-825 3925);
DISPLAY INVISIBLE (-825 3925);
FORCEPROP 2 LAST BOM_COST PVPP_KLM_VR
J 0
(-825 3925);
PAINT WHITE (-825 3925);
DISPLAY INVISIBLE (-825 3925);
FORCEPROP 2 LAST CDS_LIB mstr_discrete
J 0
(-825 3925);
PAINT MONO (-825 3925);
DISPLAY INVISIBLE (-825 3925);
FORCEPROP 2 LAST CDS_LOCATION C3T7
J 0
(-775 4025);
DISPLAY 0.617021 (-775 4025);
PAINT AQUA (-775 4025);
DISPLAY INVISIBLE (-775 4025);
FORCEPROP 1 LAST PATH I184
J 0
(-775 4075);
DISPLAY 0.978723 (-775 4075);
PAINT WHITE (-775 4075);
DISPLAY INVISIBLE (-775 4075);
FORCEPROP 2 LAST REUSE_ID 33
J 0
(-775 4125);
DISPLAY 1.042553 (-775 4125);
PAINT ORANGE (-775 4125);
DISPLAY INVISIBLE (-775 4125);
FORCEPROP 2 LAST CDS_SEC 1
J 0
(-775 4125);
DISPLAY 1.042553 (-775 4125);
PAINT ORANGE (-775 4125);
DISPLAY INVISIBLE (-775 4125);
FORCEPROP 2 LAST $SEC 1
J 0
(-775 4125);
DISPLAY 0.680851 (-775 4125);
PAINT MONO (-775 4125);
DISPLAY INVISIBLE (-775 4125);
FORCEADD GND..1
(-525 3650);
FORCEPROP 3 LASTPIN (-525 3700) SIG_NAME GND\g
J 0
(-515 3710);
DISPLAY 0.659574 (-515 3710);
PAINT MONO (-515 3710);
DISPLAY INVISIBLE (-515 3710);
FORCEPROP 2 LAST BOM_COST PVPP_KLM_VR
J 0
(-1375 3725);
DISPLAY 1.042553 (-1375 3725);
PAINT WHITE (-1375 3725);
DISPLAY INVISIBLE (-1375 3725);
FORCEPROP 2 LAST ROOM PVPP_KLM_VR
J 0
(-1100 3725);
DISPLAY 1.042553 (-1100 3725);
PAINT GREEN (-1100 3725);
DISPLAY INVISIBLE (-1100 3725);
FORCEPROP 1 LAST HDL_POWER GND
J 0
(-525 3800);
DISPLAY 0.872340 (-525 3800);
PAINT GREEN (-525 3800);
DISPLAY INVISIBLE (-525 3800);
FORCEPROP 1 LAST VOLTAGE 0
J 0
(-525 3650);
PAINT SKYBLUE (-525 3650);
DISPLAY INVISIBLE (-525 3650);
FORCEPROP 2 LAST CDS_LIB mstr_symbols
J 0
(-525 3650);
PAINT MONO (-525 3650);
DISPLAY INVISIBLE (-525 3650);
FORCEPROP 1 LAST BODY_TYPE PLUMBING
J 0
(-570 3607);
DISPLAY 0.340426 (-570 3607);
PAINT GREEN (-570 3607);
DISPLAY INVISIBLE (-570 3607);
FORCEPROP 1 LAST PATH I185
J 0
(-450 3650);
DISPLAY 0.872340 (-450 3650);
PAINT AQUA (-450 3650);
DISPLAY INVISIBLE (-450 3650);
FORCEPROP 1 LAST SIZE 1B
J 0
(-450 3600);
DISPLAY 0.872340 (-450 3600);
PAINT GREEN (-450 3600);
DISPLAY INVISIBLE (-450 3600);
FORCEADD CAP..1
(-525 3925);
FORCEPROP 1 LASTPIN (-525 4025) $PN 1
J 0
(-515 4005);
DISPLAY 0.617021 (-515 4005);
PAINT WHITE (-515 4005);
FORCEPROP 1 LASTPIN (-525 3825) $PN 2
J 0
(-515 3805);
DISPLAY 0.617021 (-515 3805);
PAINT WHITE (-515 3805);
FORCEPROP 1 LAST MATERIAL X6S
J 0
(-475 3825);
DISPLAY 0.617021 (-475 3825);
PAINT SKYBLUE (-475 3825);
FORCEPROP 1 LAST VOLTAGE 4V
J 0
(-475 3925);
DISPLAY 0.617021 (-475 3925);
PAINT SKYBLUE (-475 3925);
FORCEPROP 1 LAST PACK_TYPE 0805
J 0
(-475 3725);
DISPLAY 0.617021 (-475 3725);
PAINT SKYBLUE (-475 3725);
FORCEPROP 1 LAST TOLERANCE 20%
J 0
(-475 3875);
DISPLAY 0.617021 (-475 3875);
PAINT SKYBLUE (-475 3875);
FORCEPROP 1 LAST VALUE 47UF
J 0
(-475 3975);
DISPLAY 0.617021 (-475 3975);
PAINT SKYBLUE (-475 3975);
FORCEPROP 1 LAST PART_NUMBER C95333-006
J 0
(-475 3775);
DISPLAY 0.617021 (-475 3775);
PAINT BLUE (-475 3775);
FORCEPROP 1 LAST LOCATION C3T9
J 0
(-475 4025);
DISPLAY 0.617021 (-475 4025);
PAINT AQUA (-475 4025);
FORCEPROP 2 LAST BOM_COST PVPP_KLM_VR
J 0
(-525 3925);
PAINT WHITE (-525 3925);
DISPLAY INVISIBLE (-525 3925);
FORCEPROP 2 LAST CDS_LIB mstr_discrete
J 0
(-525 3925);
PAINT MONO (-525 3925);
DISPLAY INVISIBLE (-525 3925);
FORCEPROP 2 LAST ROOM PVPP_KLM_VR
J 0
(-525 3925);
PAINT GREEN (-525 3925);
DISPLAY INVISIBLE (-525 3925);
FORCEPROP 2 LAST CDS_LOCATION C3T9
J 0
(-475 4025);
DISPLAY 0.617021 (-475 4025);
PAINT AQUA (-475 4025);
DISPLAY INVISIBLE (-475 4025);
FORCEPROP 1 LAST PATH I186
J 0
(-475 4075);
DISPLAY 0.978723 (-475 4075);
PAINT WHITE (-475 4075);
DISPLAY INVISIBLE (-475 4075);
FORCEPROP 2 LAST REUSE_ID 33
J 0
(-475 4125);
DISPLAY 1.042553 (-475 4125);
PAINT ORANGE (-475 4125);
DISPLAY INVISIBLE (-475 4125);
FORCEPROP 2 LAST CDS_SEC 1
J 0
(-475 4125);
DISPLAY 1.042553 (-475 4125);
PAINT ORANGE (-475 4125);
DISPLAY INVISIBLE (-475 4125);
FORCEPROP 2 LAST $SEC 1
J 0
(-475 4125);
DISPLAY 0.680851 (-475 4125);
PAINT MONO (-475 4125);
DISPLAY INVISIBLE (-475 4125);
FORCEADD PVPP_ABC..1
(-450 4225);
FORCEPROP 3 LASTPIN (-450 4175) SIG_NAME PVPP_ABC\g
J 0
(-440 4185);
DISPLAY 0.659574 (-440 4185);
PAINT MONO (-440 4185);
DISPLAY INVISIBLE (-440 4185);
FORCEPROP 1 LAST VOLTAGE 2.5V
J 0
(-495 4182);
DISPLAY 0.340426 (-495 4182);
PAINT SKYBLUE (-495 4182);
DISPLAY INVISIBLE (-495 4182);
FORCEPROP 1 LAST BODY_TYPE PLUMBING
J 0
(-495 4182);
DISPLAY 0.340426 (-495 4182);
PAINT GREEN (-495 4182);
DISPLAY INVISIBLE (-495 4182);
FORCEPROP 2 LAST CDS_LIB mstr_symbols
J 0
(-450 4225);
PAINT ORANGE (-450 4225);
DISPLAY INVISIBLE (-450 4225);
FORCEPROP 1 LAST PATH I187
J 0
(-400 4250);
DISPLAY 0.872340 (-400 4250);
PAINT AQUA (-400 4250);
DISPLAY INVISIBLE (-400 4250);
FORCEPROP 1 LAST HDL_POWER PVPP_ABC
J 1
(-450 4275);
DISPLAY 0.872340 (-450 4275);
PAINT GREEN (-450 4275);
DISPLAY INVISIBLE (-450 4275);
FORCEPROP 2 LAST BOM_COST PVPP_KLM_VR
J 0
(-375 4325);
PAINT MONO (-375 4325);
DISPLAY INVISIBLE (-375 4325);
FORCEPROP 2 LAST ROOM PVPP_KLM_VR
J 0
(-200 4325);
PAINT ORANGE (-200 4325);
DISPLAY INVISIBLE (-200 4325);
FORCEADD OFFPAGE..2
(-2400 1225);
FORCEPROP 2 LAST $XR0 91 
J 0
(-2211 1225);
DISPLAY 0.638298 (-2211 1225);
PAINT MONO (-2211 1225);
FORCEPROP 2 LAST $XR1 190 
J 0
(-2121 1225);
DISPLAY 0.638298 (-2121 1225);
PAINT MONO (-2121 1225);
FORCEPROP 2 LAST BOM_COST PVPP_KLM_VR
J 0
(-3100 1300);
DISPLAY 1.042553 (-3100 1300);
PAINT WHITE (-3100 1300);
DISPLAY INVISIBLE (-3100 1300);
FORCEPROP 2 LAST ROOM PVPP_KLM_VR
J 0
(-2825 1300);
DISPLAY 1.042553 (-2825 1300);
PAINT GREEN (-2825 1300);
DISPLAY INVISIBLE (-2825 1300);
FORCEPROP 1 LAST COMMENT_BODY TRUE
J 0
(-2445 1130);
DISPLAY 0.872340 (-2445 1130);
PAINT PEACH (-2445 1130);
DISPLAY INVISIBLE (-2445 1130);
FORCEPROP 2 LAST CDS_LIB mstr_standard
J 2
(-2400 1225);
PAINT MONO (-2400 1225);
DISPLAY INVISIBLE (-2400 1225);
FORCEPROP 0 LAST TOLERANCE 1%
J 0
(-2225 1300);
PAINT SKYBLUE (-2225 1300);
DISPLAY INVISIBLE (-2225 1300);
FORCEPROP 2 LAST PATH I188
J 0
(-2200 1275);
DISPLAY 1.021277 (-2200 1275);
PAINT ORANGE (-2200 1275);
DISPLAY INVISIBLE (-2200 1275);
FORCEPROP 1 LAST OFFPAGE TRUE
J 0
(-2075 1100);
PAINT GREEN (-2075 1100);
DISPLAY INVISIBLE (-2075 1100);
FORCEADD AGND_SCSI..1
(-4025 2100);
FORCEPROP 3 LASTPIN (-4025 2150) SIG_NAME AGND_PVPP_ABC\g
J 0
(-4015 2160);
DISPLAY 0.659574 (-4015 2160);
PAINT MONO (-4015 2160);
DISPLAY INVISIBLE (-4015 2160);
FORCEPROP 1 LAST HDL_POWER AGND_PVPP_ABC
J 1
(-4000 2025);
DISPLAY 0.617021 (-4000 2025);
PAINT GREEN (-4000 2025);
FORCEPROP 2 LAST ROOM PVPP_KLM_VR
J 0
(-4175 2050);
DISPLAY 1.042553 (-4175 2050);
PAINT GREEN (-4175 2050);
DISPLAY INVISIBLE (-4175 2050);
FORCEPROP 2 LAST BOM_COST PVPP_KLM_VR
J 0
(-4175 2050);
DISPLAY 1.042553 (-4175 2050);
PAINT WHITE (-4175 2050);
DISPLAY INVISIBLE (-4175 2050);
FORCEPROP 1 LAST BODY_TYPE PLUMBING
J 0
(-4070 2057);
DISPLAY 0.340426 (-4070 2057);
PAINT GREEN (-4070 2057);
DISPLAY INVISIBLE (-4070 2057);
FORCEPROP 1 LAST VOLTAGE 0.0V
J 0
(-4070 2057);
DISPLAY 0.340426 (-4070 2057);
PAINT SKYBLUE (-4070 2057);
DISPLAY INVISIBLE (-4070 2057);
FORCEPROP 2 LAST CDS_LIB mstr_symbols
J 0
(-4025 2100);
PAINT MONO (-4025 2100);
DISPLAY INVISIBLE (-4025 2100);
FORCEPROP 1 LAST PATH I189
J 0
(-3950 2100);
DISPLAY 0.872340 (-3950 2100);
PAINT AQUA (-3950 2100);
DISPLAY INVISIBLE (-3950 2100);
FORCEADD AGND_SCSI..1
(-4400 1600);
FORCEPROP 3 LASTPIN (-4400 1650) SIG_NAME AGND_PVPP_ABC\g
J 0
(-4390 1660);
DISPLAY 0.659574 (-4390 1660);
PAINT MONO (-4390 1660);
DISPLAY INVISIBLE (-4390 1660);
FORCEPROP 1 LAST HDL_POWER AGND_PVPP_ABC
J 1
(-4375 1525);
DISPLAY 0.617021 (-4375 1525);
PAINT GREEN (-4375 1525);
FORCEPROP 1 LAST BODY_TYPE PLUMBING
J 0
(-4445 1557);
DISPLAY 0.340426 (-4445 1557);
PAINT GREEN (-4445 1557);
DISPLAY INVISIBLE (-4445 1557);
FORCEPROP 2 LAST CDS_LIB mstr_symbols
J 0
(-4400 1600);
PAINT MONO (-4400 1600);
DISPLAY INVISIBLE (-4400 1600);
FORCEPROP 1 LAST VOLTAGE 0
J 0
(-4375 1625);
DISPLAY 1.021277 (-4375 1625);
PAINT SKYBLUE (-4375 1625);
DISPLAY INVISIBLE (-4375 1625);
FORCEPROP 1 LAST PATH I190
J 0
(-4325 1600);
DISPLAY 0.872340 (-4325 1600);
PAINT AQUA (-4325 1600);
DISPLAY INVISIBLE (-4325 1600);
FORCEADD P3V3_STBY..1
(-3875 1775);
FORCEPROP 3 LASTPIN (-3875 1725) SIG_NAME P3V3_STBY\g
J 0
(-3865 1735);
DISPLAY 0.659574 (-3865 1735);
PAINT MONO (-3865 1735);
DISPLAY INVISIBLE (-3865 1735);
FORCEPROP 1 LAST HDL_POWER P3V3_STBY
J 0
(-4175 1650);
DISPLAY 0.872340 (-4175 1650);
PAINT ORANGE (-4175 1650);
DISPLAY INVISIBLE (-4175 1650);
FORCEPROP 2 LAST CDS_LIB mstr_symbols
J 0
(-3875 1775);
PAINT MONO (-3875 1775);
DISPLAY INVISIBLE (-3875 1775);
FORCEPROP 1 LAST BODY_TYPE PLUMBING
J 0
(-3920 1732);
DISPLAY 0.340426 (-3920 1732);
PAINT GREEN (-3920 1732);
DISPLAY INVISIBLE (-3920 1732);
FORCEPROP 1 LAST VOLTAGE +3.3V
J 0
(-3675 1925);
DISPLAY 1.021277 (-3675 1925);
PAINT SKYBLUE (-3675 1925);
DISPLAY INVISIBLE (-3675 1925);
FORCEPROP 1 LAST SIZE 1B
J 0
(-3830 1797);
DISPLAY 0.340426 (-3830 1797);
PAINT GREEN (-3830 1797);
DISPLAY INVISIBLE (-3830 1797);
FORCEPROP 1 LAST PATH I192
J 0
(-3830 1777);
DISPLAY 0.340426 (-3830 1777);
PAINT GREEN (-3830 1777);
DISPLAY INVISIBLE (-3830 1777);
FORCEADD NCP3232L..1
(-3450 3125);
FORCEPROP 2 LASTPIN (-3950 2275) $PN 5
J 2
(-3960 2285);
DISPLAY 0.617021 (-3960 2285);
PAINT ORANGE (-3960 2285);
FORCEPROP 1 LAST PART_NUMBER H86355-001
J 0
(-3900 2125);
DISPLAY 0.617021 (-3900 2125);
PAINT BLUE (-3900 2125);
FORCEPROP 2 LASTPIN (-3950 2875) $PN 4
J 2
(-3960 2885);
DISPLAY 0.617021 (-3960 2885);
PAINT ORANGE (-3960 2885);
FORCEPROP 2 LASTPIN (-3950 2775) $PN 7
J 2
(-3960 2785);
DISPLAY 0.617021 (-3960 2785);
PAINT ORANGE (-3960 2785);
FORCEPROP 2 LASTPIN (-3950 2975) $PN 1
J 2
(-3960 2985);
DISPLAY 0.617021 (-3960 2985);
PAINT ORANGE (-3960 2985);
FORCEPROP 2 LASTPIN (-3950 3075) $PN 40
J 2
(-3960 3085);
DISPLAY 0.617021 (-3960 3085);
PAINT ORANGE (-3960 3085);
FORCEPROP 2 LASTPIN (-3950 3175) $PN 6
J 2
(-3960 3185);
DISPLAY 0.617021 (-3960 3185);
PAINT ORANGE (-3960 3185);
FORCEPROP 2 LASTPIN (-3950 3275) $PN 38
J 2
(-3960 3285);
DISPLAY 0.617021 (-3960 3285);
PAINT ORANGE (-3960 3285);
FORCEPROP 2 LASTPIN (-3950 3525) $PN 11
J 2
(-3960 3535);
DISPLAY 0.617021 (-3960 3535);
PAINT ORANGE (-3960 3535);
FORCEPROP 2 LASTPIN (-3950 3475) $PN 10
J 2
(-3960 3485);
DISPLAY 0.617021 (-3960 3485);
PAINT ORANGE (-3960 3485);
FORCEPROP 2 LASTPIN (-3950 3425) $PN 9
J 2
(-3960 3435);
DISPLAY 0.617021 (-3960 3435);
PAINT ORANGE (-3960 3435);
FORCEPROP 2 LASTPIN (-3950 3375) $PN 8
J 2
(-3960 3385);
DISPLAY 0.617021 (-3960 3385);
PAINT ORANGE (-3960 3385);
FORCEPROP 2 LASTPIN (-3950 3575) $PN 12
J 2
(-3960 3585);
DISPLAY 0.617021 (-3960 3585);
PAINT ORANGE (-3960 3585);
FORCEPROP 2 LASTPIN (-3950 3625) $PN 13
J 2
(-3960 3635);
DISPLAY 0.617021 (-3960 3635);
PAINT ORANGE (-3960 3635);
FORCEPROP 2 LASTPIN (-3950 3675) $PN 14
J 2
(-3960 3685);
DISPLAY 0.617021 (-3960 3685);
PAINT ORANGE (-3960 3685);
FORCEPROP 2 LASTPIN (-3950 3725) $PN 42
J 2
(-3960 3735);
DISPLAY 0.617021 (-3960 3735);
PAINT ORANGE (-3960 3735);
FORCEPROP 2 LASTPIN (-3950 3825) $PN 39
J 2
(-3960 3835);
DISPLAY 0.617021 (-3960 3835);
PAINT ORANGE (-3960 3835);
FORCEPROP 1 LAST MATERIAL IC
J 0
(-3900 4025);
DISPLAY 0.617021 (-3900 4025);
PAINT SKYBLUE (-3900 4025);
FORCEPROP 2 LASTPIN (-2950 2275) $PN 41
J 0
(-2940 2285);
DISPLAY 0.617021 (-2940 2285);
PAINT ORANGE (-2940 2285);
FORCEPROP 2 LASTPIN (-2950 2325) $PN 16
J 0
(-2940 2335);
DISPLAY 0.617021 (-2940 2335);
PAINT ORANGE (-2940 2335);
FORCEPROP 2 LASTPIN (-2950 2375) $PN 17
J 0
(-2940 2385);
DISPLAY 0.617021 (-2940 2385);
PAINT ORANGE (-2940 2385);
FORCEPROP 2 LASTPIN (-2950 2425) $PN 18
J 0
(-2940 2435);
DISPLAY 0.617021 (-2940 2435);
PAINT ORANGE (-2940 2435);
FORCEPROP 2 LASTPIN (-2950 2475) $PN 19
J 0
(-2940 2485);
DISPLAY 0.617021 (-2940 2485);
PAINT ORANGE (-2940 2485);
FORCEPROP 2 LASTPIN (-2950 2525) $PN 20
J 0
(-2940 2535);
DISPLAY 0.617021 (-2940 2535);
PAINT ORANGE (-2940 2535);
FORCEPROP 2 LASTPIN (-2950 2775) $PN 25
J 0
(-2940 2785);
DISPLAY 0.617021 (-2940 2785);
PAINT ORANGE (-2940 2785);
FORCEPROP 2 LASTPIN (-2950 2725) $PN 24
J 0
(-2940 2735);
DISPLAY 0.617021 (-2940 2735);
PAINT ORANGE (-2940 2735);
FORCEPROP 2 LASTPIN (-2950 2675) $PN 23
J 0
(-2940 2685);
DISPLAY 0.617021 (-2940 2685);
PAINT ORANGE (-2940 2685);
FORCEPROP 2 LASTPIN (-2950 2625) $PN 22
J 0
(-2940 2635);
DISPLAY 0.617021 (-2940 2635);
PAINT ORANGE (-2940 2635);
FORCEPROP 2 LASTPIN (-2950 2575) $PN 21
J 0
(-2940 2585);
DISPLAY 0.617021 (-2940 2585);
PAINT ORANGE (-2940 2585);
FORCEPROP 2 LASTPIN (-2950 2825) $PN 26
J 0
(-2940 2835);
DISPLAY 0.617021 (-2940 2835);
PAINT ORANGE (-2940 2835);
FORCEPROP 2 LASTPIN (-2950 2875) $PN 27
J 0
(-2940 2885);
DISPLAY 0.617021 (-2940 2885);
PAINT ORANGE (-2940 2885);
FORCEPROP 2 LASTPIN (-2950 2925) $PN 28
J 0
(-2940 2935);
DISPLAY 0.617021 (-2940 2935);
PAINT ORANGE (-2940 2935);
FORCEPROP 2 LASTPIN (-2950 2975) $PN 37
J 0
(-2940 2985);
DISPLAY 0.617021 (-2940 2985);
PAINT ORANGE (-2940 2985);
FORCEPROP 2 LASTPIN (-2950 3075) $PN 3
J 0
(-2940 3085);
DISPLAY 0.617021 (-2940 3085);
PAINT ORANGE (-2940 3085);
FORCEPROP 2 LASTPIN (-2950 3175) $PN 2
J 0
(-2940 3185);
DISPLAY 0.617021 (-2940 3185);
PAINT ORANGE (-2940 3185);
FORCEPROP 2 LASTPIN (-2950 3275) $PN 35
J 0
(-2940 3285);
DISPLAY 0.617021 (-2940 3285);
PAINT ORANGE (-2940 3285);
FORCEPROP 2 LASTPIN (-2950 3525) $PN 31
J 0
(-2940 3535);
DISPLAY 0.617021 (-2940 3535);
PAINT ORANGE (-2940 3535);
FORCEPROP 2 LASTPIN (-2950 3475) $PN 30
J 0
(-2940 3485);
DISPLAY 0.617021 (-2940 3485);
PAINT ORANGE (-2940 3485);
FORCEPROP 2 LASTPIN (-2950 3425) $PN 29
J 0
(-2940 3435);
DISPLAY 0.617021 (-2940 3435);
PAINT ORANGE (-2940 3435);
FORCEPROP 2 LASTPIN (-2950 3375) $PN 15
J 0
(-2940 3385);
DISPLAY 0.617021 (-2940 3385);
PAINT ORANGE (-2940 3385);
FORCEPROP 2 LASTPIN (-2950 3625) $PN 33
J 0
(-2940 3635);
DISPLAY 0.617021 (-2940 3635);
PAINT ORANGE (-2940 3635);
FORCEPROP 2 LASTPIN (-2950 3675) $PN 34
J 0
(-2940 3685);
DISPLAY 0.617021 (-2940 3685);
PAINT ORANGE (-2940 3685);
FORCEPROP 2 LASTPIN (-2950 3725) $PN 43
J 0
(-2940 3735);
DISPLAY 0.617021 (-2940 3735);
PAINT ORANGE (-2940 3735);
FORCEPROP 2 LASTPIN (-2950 3575) $PN 32
J 0
(-2940 3585);
DISPLAY 0.617021 (-2940 3585);
PAINT ORANGE (-2940 3585);
FORCEPROP 2 LASTPIN (-2950 3825) $PN 36
J 0
(-2940 3835);
DISPLAY 0.617021 (-2940 3835);
PAINT ORANGE (-2940 3835);
FORCEPROP 1 LAST LOCATION EU7F1
J 0
(-3900 4075);
DISPLAY 0.617021 (-3900 4075);
PAINT AQUA (-3900 4075);
FORCEPROP 1 LAST PATH I193
J 0
(-3400 4025);
PAINT GREEN (-3400 4025);
DISPLAY INVISIBLE (-3400 4025);
FORCEPROP 1 LAST CDS_LMAN_SYM_OUTLINE -450,850,450,-900
J 0
(-3450 3125);
DISPLAY 0.468085 (-3450 3125);
PAINT GREEN (-3450 3125);
DISPLAY INVISIBLE (-3450 3125);
FORCEPROP 2 LAST CDS_LIB mstr_vreg
J 0
(-3450 3125);
PAINT ORANGE (-3450 3125);
DISPLAY INVISIBLE (-3450 3125);
FORCEPROP 2 LAST CDS_LOCATION EU7F1
J 0
(-3900 4075);
DISPLAY 0.617021 (-3900 4075);
PAINT AQUA (-3900 4075);
DISPLAY INVISIBLE (-3900 4075);
FORCEPROP 2 LAST SEC 1
J 0
(-3900 4125);
DISPLAY 0.680851 (-3900 4125);
PAINT MONO (-3900 4125);
DISPLAY INVISIBLE (-3900 4125);
FORCEPROP 1 LAST PACK_TYPE SM
J 0
(-3900 4125);
PAINT SKYBLUE (-3900 4125);
DISPLAY INVISIBLE (-3900 4125);
FORCEPROP 2 LAST SEC_TYPE SM
J 0
(-3900 4125);
DISPLAY 1.021277 (-3900 4125);
PAINT ORANGE (-3900 4125);
DISPLAY INVISIBLE (-3900 4125);
FORCEADD CAP..1
(-4725 2425);
FORCEPROP 1 LASTPIN (-4725 2525) $PN 1
J 0
(-4715 2505);
DISPLAY 0.617021 (-4715 2505);
PAINT ORANGE (-4715 2505);
FORCEPROP 1 LASTPIN (-4725 2325) $PN 2
J 0
(-4715 2305);
DISPLAY 0.617021 (-4715 2305);
PAINT ORANGE (-4715 2305);
FORCEPROP 1 LAST MATERIAL X7R
J 0
(-4675 2225);
DISPLAY 0.617021 (-4675 2225);
PAINT SKYBLUE (-4675 2225);
FORCEPROP 1 LAST VOLTAGE 16V
J 0
(-4650 2425);
DISPLAY 0.617021 (-4650 2425);
PAINT SKYBLUE (-4650 2425);
FORCEPROP 1 LAST PACK_TYPE 0402
J 0
(-4675 2325);
DISPLAY 0.617021 (-4675 2325);
PAINT SKYBLUE (-4675 2325);
FORCEPROP 1 LAST TOLERANCE 10%
J 0
(-4650 2375);
DISPLAY 0.617021 (-4650 2375);
PAINT SKYBLUE (-4650 2375);
FORCEPROP 1 LAST VALUE 0.027UF
J 0
(-4675 2475);
DISPLAY 0.617021 (-4675 2475);
PAINT SKYBLUE (-4675 2475);
FORCEPROP 1 LAST PART_NUMBER A36096-129
J 0
(-4700 2275);
DISPLAY 0.617021 (-4700 2275);
PAINT BLUE (-4700 2275);
FORCEPROP 1 LAST LOCATION C7F10
J 0
(-4675 2525);
DISPLAY 0.617021 (-4675 2525);
PAINT AQUA (-4675 2525);
FORCEPROP 2 LAST CDS_LOCATION C7F10
J 0
(-4675 2525);
DISPLAY 0.617021 (-4675 2525);
PAINT AQUA (-4675 2525);
DISPLAY INVISIBLE (-4675 2525);
FORCEPROP 2 LAST CDS_LIB mstr_discrete
J 0
(-4725 2425);
PAINT MONO (-4725 2425);
DISPLAY INVISIBLE (-4725 2425);
FORCEPROP 2 LAST ROOM PVPP_KLM_VR
J 0
(-4675 2550);
PAINT GREEN (-4675 2550);
DISPLAY INVISIBLE (-4675 2550);
FORCEPROP 2 LAST BOM_COST PVPP_KLM_VR
J 0
(-4675 2575);
DISPLAY 1.042553 (-4675 2575);
PAINT WHITE (-4675 2575);
DISPLAY INVISIBLE (-4675 2575);
FORCEPROP 2 LAST REUSE_ID 26
J 0
(-4675 2625);
DISPLAY 1.042553 (-4675 2625);
PAINT ORANGE (-4675 2625);
DISPLAY INVISIBLE (-4675 2625);
FORCEPROP 2 LAST SEC_TYPE 0402
J 0
(-4675 2625);
DISPLAY 1.021277 (-4675 2625);
PAINT ORANGE (-4675 2625);
DISPLAY INVISIBLE (-4675 2625);
FORCEPROP 2 LAST SEC 1
J 0
(-4675 2625);
PAINT MONO (-4675 2625);
DISPLAY INVISIBLE (-4675 2625);
FORCEPROP 1 LAST PATH I194
J 0
(-4675 2575);
DISPLAY 0.978723 (-4675 2575);
PAINT WHITE (-4675 2575);
DISPLAY INVISIBLE (-4675 2575);
FORCEADD AGND_SCSI..1
(-4725 2200);
FORCEPROP 3 LASTPIN (-4725 2250) SIG_NAME AGND_PVPP_ABC\g
J 0
(-4715 2260);
DISPLAY 0.659574 (-4715 2260);
PAINT MONO (-4715 2260);
DISPLAY INVISIBLE (-4715 2260);
FORCEPROP 1 LAST HDL_POWER AGND_PVPP_ABC
J 1
(-4700 2125);
DISPLAY 0.617021 (-4700 2125);
PAINT GREEN (-4700 2125);
FORCEPROP 2 LAST ROOM PVPP_KLM_VR
J 0
(-4875 2150);
DISPLAY 1.042553 (-4875 2150);
PAINT GREEN (-4875 2150);
DISPLAY INVISIBLE (-4875 2150);
FORCEPROP 2 LAST BOM_COST PVPP_KLM_VR
J 0
(-4875 2150);
DISPLAY 1.042553 (-4875 2150);
PAINT WHITE (-4875 2150);
DISPLAY INVISIBLE (-4875 2150);
FORCEPROP 1 LAST PATH I195
J 0
(-4650 2200);
DISPLAY 0.872340 (-4650 2200);
PAINT AQUA (-4650 2200);
DISPLAY INVISIBLE (-4650 2200);
FORCEPROP 1 LAST BODY_TYPE PLUMBING
J 0
(-4770 2157);
DISPLAY 0.340426 (-4770 2157);
PAINT GREEN (-4770 2157);
DISPLAY INVISIBLE (-4770 2157);
FORCEPROP 2 LAST CDS_LIB mstr_symbols
J 0
(-4725 2200);
PAINT MONO (-4725 2200);
DISPLAY INVISIBLE (-4725 2200);
FORCEPROP 1 LAST VOLTAGE 0.0V
J 0
(-4770 2157);
DISPLAY 0.340426 (-4770 2157);
PAINT SKYBLUE (-4770 2157);
DISPLAY INVISIBLE (-4770 2157);
FORCEADD GND..1
(-2725 2175);
FORCEPROP 3 LASTPIN (-2725 2225) SIG_NAME GND\g
J 0
(-2715 2235);
DISPLAY 0.659574 (-2715 2235);
PAINT MONO (-2715 2235);
DISPLAY INVISIBLE (-2715 2235);
FORCEPROP 2 LAST BOM_COST PVPP_KLM_VR
J 0
(-3625 2325);
DISPLAY 1.042553 (-3625 2325);
PAINT WHITE (-3625 2325);
DISPLAY INVISIBLE (-3625 2325);
FORCEPROP 2 LAST ROOM PVPP_KLM_VR
J 0
(-3375 2325);
PAINT GREEN (-3375 2325);
DISPLAY INVISIBLE (-3375 2325);
FORCEPROP 1 LAST BODY_TYPE PLUMBING
J 0
(-2770 2132);
DISPLAY 0.340426 (-2770 2132);
PAINT GREEN (-2770 2132);
DISPLAY INVISIBLE (-2770 2132);
FORCEPROP 2 LAST CDS_LIB mstr_symbols
J 0
(-2725 2175);
PAINT MONO (-2725 2175);
DISPLAY INVISIBLE (-2725 2175);
FORCEPROP 1 LAST VOLTAGE 0
J 0
(-2725 2250);
PAINT SKYBLUE (-2725 2250);
DISPLAY INVISIBLE (-2725 2250);
FORCEPROP 1 LAST PATH I196
J 0
(-2650 2175);
DISPLAY 0.872340 (-2650 2175);
PAINT AQUA (-2650 2175);
DISPLAY INVISIBLE (-2650 2175);
FORCEPROP 1 LAST SIZE 1B
J 0
(-2650 2200);
DISPLAY 0.893617 (-2650 2200);
PAINT GREEN (-2650 2200);
DISPLAY INVISIBLE (-2650 2200);
FORCEPROP 1 LAST HDL_POWER GND
J 0
(-2725 2400);
DISPLAY 0.893617 (-2725 2400);
PAINT GREEN (-2725 2400);
DISPLAY INVISIBLE (-2725 2400);
FORCEADD CAP..2
R 2
(-2075 3075);
FORCEPROP 1 LAST PART_NUMBER A36095-026
J 1
(-2300 2975);
DISPLAY 0.617021 (-2300 2975);
PAINT BLUE (-2300 2975);
FORCEPROP 1 LAST VOLTAGE 50V
J 2
(-2075 2975);
DISPLAY 0.617021 (-2075 2975);
PAINT SKYBLUE (-2075 2975);
FORCEPROP 1 LASTPIN (-2175 3075) $PN 2
J 2
(-2160 3090);
DISPLAY 0.617021 (-2160 3090);
PAINT ORANGE (-2160 3090);
FORCEPROP 1 LAST PACK_TYPE 0402LF
J 1
(-2050 2925);
DISPLAY 0.617021 (-2050 2925);
PAINT SKYBLUE (-2050 2925);
FORCEPROP 1 LAST VALUE 100.0PF
J 0
(-2075 2975);
DISPLAY 0.617021 (-2075 2975);
PAINT SKYBLUE (-2075 2975);
FORCEPROP 1 LAST LOCATION C7F9
J 1
(-2075 3125);
DISPLAY 0.617021 (-2075 3125);
PAINT AQUA (-2075 3125);
FORCEPROP 1 LAST TOLERANCE 5%
J 0
(-1875 2975);
DISPLAY 0.617021 (-1875 2975);
PAINT SKYBLUE (-1875 2975);
FORCEPROP 1 LAST MATERIAL COG
J 2
(-1675 2975);
DISPLAY 0.617021 (-1675 2975);
PAINT SKYBLUE (-1675 2975);
FORCEPROP 1 LASTPIN (-1975 3075) $PN 1
J 2
(-1965 3090);
DISPLAY 0.617021 (-1965 3090);
PAINT ORANGE (-1965 3090);
FORCEPROP 2 LAST ROOM PVPP_KLM_VR
J 2
(-2075 3200);
DISPLAY 0.765957 (-2075 3200);
PAINT GREEN (-2075 3200);
DISPLAY INVISIBLE (-2075 3200);
FORCEPROP 1 LAST PATH I199
J 2
(-2075 3275);
DISPLAY 0.978723 (-2075 3275);
PAINT WHITE (-2075 3275);
DISPLAY INVISIBLE (-2075 3275);
FORCEPROP 2 LAST CDS_LOCATION C7F9
J 1
(-2075 3125);
DISPLAY 0.617021 (-2075 3125);
PAINT AQUA (-2075 3125);
DISPLAY INVISIBLE (-2075 3125);
FORCEPROP 2 LAST BOM_COST PVPP_KLM_VR
J 0
(-2120 3235);
DISPLAY 1.042553 (-2120 3235);
PAINT WHITE (-2120 3235);
DISPLAY INVISIBLE (-2120 3235);
FORCEPROP 2 LAST CDS_LIB mstr_discrete
J 0
(-2075 3075);
PAINT ORANGE (-2075 3075);
DISPLAY INVISIBLE (-2075 3075);
FORCEPROP 2 LAST SEC 1
J 0
(-2075 3325);
DISPLAY 0.680851 (-2075 3325);
PAINT MONO (-2075 3325);
DISPLAY INVISIBLE (-2075 3325);
FORCEPROP 2 LAST REUSE_ID 27
J 0
(-2075 3325);
DISPLAY 1.042553 (-2075 3325);
PAINT ORANGE (-2075 3325);
DISPLAY INVISIBLE (-2075 3325);
FORCEPROP 2 LAST SEC_TYPE 0402LF
J 0
(-2075 3325);
DISPLAY 1.021277 (-2075 3325);
PAINT ORANGE (-2075 3325);
DISPLAY INVISIBLE (-2075 3325);
FORCEADD CAP..2
R 2
(-2500 2700);
FORCEPROP 1 LASTPIN (-2600 2700) $PN 2
J 2
(-2585 2715);
DISPLAY 0.617021 (-2585 2715);
PAINT ORANGE (-2585 2715);
FORCEPROP 1 LAST MATERIAL X7R
J 2
(-2500 2525);
DISPLAY 0.617021 (-2500 2525);
PAINT SKYBLUE (-2500 2525);
FORCEPROP 1 LAST VOLTAGE 50V
J 2
(-2500 2575);
DISPLAY 0.617021 (-2500 2575);
PAINT SKYBLUE (-2500 2575);
FORCEPROP 1 LAST PACK_TYPE 0402LF
J 1
(-2500 2475);
DISPLAY 0.617021 (-2500 2475);
PAINT SKYBLUE (-2500 2475);
FORCEPROP 1 LAST PART_NUMBER A36096-075
J 1
(-2475 2625);
DISPLAY 0.617021 (-2475 2625);
PAINT BLUE (-2475 2625);
FORCEPROP 1 LAST LOCATION C7F12
J 1
(-2500 2775);
DISPLAY 0.617021 (-2500 2775);
PAINT AQUA (-2500 2775);
FORCEPROP 1 LAST TOLERANCE 10%
J 0
(-2500 2525);
DISPLAY 0.617021 (-2500 2525);
PAINT SKYBLUE (-2500 2525);
FORCEPROP 1 LASTPIN (-2400 2700) $PN 1
J 2
(-2390 2715);
DISPLAY 0.617021 (-2390 2715);
PAINT ORANGE (-2390 2715);
FORCEPROP 1 LAST VALUE 2200PF
J 0
(-2475 2575);
DISPLAY 0.617021 (-2475 2575);
PAINT SKYBLUE (-2475 2575);
FORCEPROP 2 LAST ROOM PVPP_KLM_VR
J 2
(-2500 2825);
DISPLAY 0.765957 (-2500 2825);
PAINT GREEN (-2500 2825);
DISPLAY INVISIBLE (-2500 2825);
FORCEPROP 1 LAST PATH I200
J 2
(-2500 2900);
DISPLAY 0.978723 (-2500 2900);
PAINT WHITE (-2500 2900);
DISPLAY INVISIBLE (-2500 2900);
FORCEPROP 2 LAST CDS_LOCATION C7F12
J 1
(-2500 2775);
DISPLAY 0.617021 (-2500 2775);
PAINT AQUA (-2500 2775);
DISPLAY INVISIBLE (-2500 2775);
FORCEPROP 2 LAST SEC 1
J 0
(-2500 2950);
DISPLAY 0.680851 (-2500 2950);
PAINT MONO (-2500 2950);
DISPLAY INVISIBLE (-2500 2950);
FORCEPROP 2 LAST BOM_COST PVPP_KLM_VR
J 0
(-2545 2860);
DISPLAY 1.042553 (-2545 2860);
PAINT WHITE (-2545 2860);
DISPLAY INVISIBLE (-2545 2860);
FORCEPROP 2 LAST REUSE_ID 27
J 0
(-2500 2950);
DISPLAY 1.042553 (-2500 2950);
PAINT ORANGE (-2500 2950);
DISPLAY INVISIBLE (-2500 2950);
FORCEPROP 2 LAST CDS_LIB mstr_discrete
J 0
(-2500 2700);
PAINT ORANGE (-2500 2700);
DISPLAY INVISIBLE (-2500 2700);
FORCEPROP 2 LAST SEC_TYPE 0402LF
J 0
(-2500 2950);
DISPLAY 1.021277 (-2500 2950);
PAINT ORANGE (-2500 2950);
DISPLAY INVISIBLE (-2500 2950);
FORCEADD RES..1
(-1800 2700);
FORCEPROP 1 LAST WATTAGE 1/16W
J 2
(-1825 2525);
DISPLAY 0.617021 (-1825 2525);
PAINT SKYBLUE (-1825 2525);
FORCEPROP 1 LAST MATERIAL CHIP
J 0
(-1800 2525);
DISPLAY 0.617021 (-1800 2525);
PAINT SKYBLUE (-1800 2525);
FORCEPROP 1 LAST VALUE 7.87K
J 2
(-1900 2575);
DISPLAY 0.617021 (-1900 2575);
PAINT SKYBLUE (-1900 2575);
FORCEPROP 1 LASTPIN (-1900 2700) $PN 1
J 0
(-1888 2712);
DISPLAY 0.617021 (-1888 2712);
PAINT ORANGE (-1888 2712);
FORCEPROP 1 LAST PART_NUMBER G21796-242
J 0
(-1950 2625);
DISPLAY 0.617021 (-1950 2625);
PAINT BLUE (-1950 2625);
FORCEPROP 1 LAST LOCATION R7F18
J 0
(-1850 2750);
DISPLAY 0.617021 (-1850 2750);
PAINT AQUA (-1850 2750);
FORCEPROP 1 LAST TOLERANCE 1.0%
J 0
(-1850 2575);
DISPLAY 0.617021 (-1850 2575);
PAINT SKYBLUE (-1850 2575);
FORCEPROP 1 LASTPIN (-1700 2700) $PN 2
J 0
(-1738 2712);
DISPLAY 0.617021 (-1738 2712);
PAINT ORANGE (-1738 2712);
FORCEPROP 1 LAST PACK_TYPE 0402
J 0
(-1750 2575);
DISPLAY 0.617021 (-1750 2575);
PAINT SKYBLUE (-1750 2575);
FORCEPROP 2 LAST CDS_LIB mstr_discrete
J 0
(-1800 2700);
PAINT MONO (-1800 2700);
DISPLAY INVISIBLE (-1800 2700);
FORCEPROP 2 LAST BOM_COST PVPP_KLM_VR
J 0
(-1800 2700);
PAINT WHITE (-1800 2700);
DISPLAY INVISIBLE (-1800 2700);
FORCEPROP 2 LAST CDS_LOCATION R7F18
J 0
(-1850 2750);
DISPLAY 0.617021 (-1850 2750);
PAINT AQUA (-1850 2750);
DISPLAY INVISIBLE (-1850 2750);
FORCEPROP 2 LAST ROOM PVPP_KLM_VR
J 0
(-1800 2700);
PAINT GREEN (-1800 2700);
DISPLAY INVISIBLE (-1800 2700);
FORCEPROP 2 LAST SEC_TYPE 0402
J 0
(-1850 2900);
DISPLAY 1.021277 (-1850 2900);
PAINT ORANGE (-1850 2900);
DISPLAY INVISIBLE (-1850 2900);
FORCEPROP 1 LAST PATH I201
J 0
(-1850 2850);
DISPLAY 0.978723 (-1850 2850);
PAINT WHITE (-1850 2850);
DISPLAY INVISIBLE (-1850 2850);
FORCEPROP 2 LAST SEC 1
J 0
(-1850 2900);
PAINT MONO (-1850 2900);
DISPLAY INVISIBLE (-1850 2900);
FORCEPROP 2 LAST REUSE_ID 13
J 0
(-1850 2900);
DISPLAY 1.042553 (-1850 2900);
PAINT ORANGE (-1850 2900);
DISPLAY INVISIBLE (-1850 2900);
FORCEADD CAP..1
(-5375 2625);
FORCEPROP 1 LASTPIN (-5375 2525) $PN 2
J 0
(-5365 2505);
DISPLAY 0.617021 (-5365 2505);
PAINT ORANGE (-5365 2505);
FORCEPROP 1 LAST MATERIAL X6S
J 0
(-5325 2425);
DISPLAY 0.617021 (-5325 2425);
PAINT SKYBLUE (-5325 2425);
FORCEPROP 1 LAST PACK_TYPE 0603
J 0
(-5325 2525);
DISPLAY 0.617021 (-5325 2525);
PAINT SKYBLUE (-5325 2525);
FORCEPROP 1 LASTPIN (-5375 2725) $PN 1
J 0
(-5365 2705);
DISPLAY 0.617021 (-5365 2705);
PAINT ORANGE (-5365 2705);
FORCEPROP 1 LAST LOCATION C3T11
J 0
(-5325 2725);
DISPLAY 0.617021 (-5325 2725);
PAINT AQUA (-5325 2725);
FORCEPROP 1 LAST VALUE 4.7UF
J 0
(-5325 2675);
DISPLAY 0.617021 (-5325 2675);
PAINT SKYBLUE (-5325 2675);
FORCEPROP 1 LAST VOLTAGE 6.3V
J 0
(-5300 2625);
DISPLAY 0.617021 (-5300 2625);
PAINT SKYBLUE (-5300 2625);
FORCEPROP 1 LAST TOLERANCE 10%
J 0
(-5300 2575);
DISPLAY 0.617021 (-5300 2575);
PAINT SKYBLUE (-5300 2575);
FORCEPROP 1 LAST PART_NUMBER E15431-003
J 0
(-5350 2475);
DISPLAY 0.617021 (-5350 2475);
PAINT BLUE (-5350 2475);
FORCEPROP 2 LAST ROOM PVPP_KLM_VR
J 0
(-5325 2750);
PAINT GREEN (-5325 2750);
DISPLAY INVISIBLE (-5325 2750);
FORCEPROP 2 LAST CDS_LIB mstr_discrete
J 0
(-5375 2625);
PAINT MONO (-5375 2625);
DISPLAY INVISIBLE (-5375 2625);
FORCEPROP 2 LAST CDS_LOCATION C3T11
J 0
(-5325 2725);
DISPLAY 0.617021 (-5325 2725);
PAINT AQUA (-5325 2725);
DISPLAY INVISIBLE (-5325 2725);
FORCEPROP 1 LAST PATH I202
J 0
(-5325 2775);
DISPLAY 0.978723 (-5325 2775);
PAINT WHITE (-5325 2775);
DISPLAY INVISIBLE (-5325 2775);
FORCEPROP 2 LAST BOM_COST PVPP_KLM_VR
J 0
(-5325 2775);
DISPLAY 1.042553 (-5325 2775);
PAINT WHITE (-5325 2775);
DISPLAY INVISIBLE (-5325 2775);
FORCEPROP 2 LAST SEC_TYPE 0603
J 0
(-5325 2825);
DISPLAY 1.021277 (-5325 2825);
PAINT ORANGE (-5325 2825);
DISPLAY INVISIBLE (-5325 2825);
FORCEPROP 2 LAST REUSE_ID 26
J 0
(-5325 2825);
DISPLAY 1.042553 (-5325 2825);
PAINT ORANGE (-5325 2825);
DISPLAY INVISIBLE (-5325 2825);
FORCEPROP 2 LAST SEC 1
J 0
(-5325 2825);
PAINT MONO (-5325 2825);
DISPLAY INVISIBLE (-5325 2825);
FORCEADD AGND_SCSI..1
(-5375 2325);
FORCEPROP 3 LASTPIN (-5375 2375) SIG_NAME AGND_PVPP_ABC\g
J 0
(-5365 2385);
DISPLAY 0.659574 (-5365 2385);
PAINT MONO (-5365 2385);
DISPLAY INVISIBLE (-5365 2385);
FORCEPROP 1 LAST HDL_POWER AGND_PVPP_ABC
J 1
(-5350 2250);
DISPLAY 0.617021 (-5350 2250);
PAINT GREEN (-5350 2250);
FORCEPROP 1 LAST VOLTAGE 0.0V
J 0
(-5420 2282);
DISPLAY 0.340426 (-5420 2282);
PAINT SKYBLUE (-5420 2282);
DISPLAY INVISIBLE (-5420 2282);
FORCEPROP 2 LAST BOM_COST PVPP_KLM_VR
J 0
(-5525 2275);
DISPLAY 1.042553 (-5525 2275);
PAINT WHITE (-5525 2275);
DISPLAY INVISIBLE (-5525 2275);
FORCEPROP 1 LAST BODY_TYPE PLUMBING
J 0
(-5420 2282);
DISPLAY 0.340426 (-5420 2282);
PAINT GREEN (-5420 2282);
DISPLAY INVISIBLE (-5420 2282);
FORCEPROP 2 LAST ROOM PVPP_KLM_VR
J 0
(-5525 2275);
DISPLAY 1.042553 (-5525 2275);
PAINT GREEN (-5525 2275);
DISPLAY INVISIBLE (-5525 2275);
FORCEPROP 2 LAST CDS_LIB mstr_symbols
J 0
(-5375 2325);
PAINT MONO (-5375 2325);
DISPLAY INVISIBLE (-5375 2325);
FORCEPROP 1 LAST PATH I203
J 0
(-5300 2325);
DISPLAY 0.872340 (-5300 2325);
PAINT AQUA (-5300 2325);
DISPLAY INVISIBLE (-5300 2325);
FORCEADD AGND_SCSI..1
(-5025 2950);
FORCEPROP 3 LASTPIN (-5025 3000) SIG_NAME AGND_PVPP_ABC\g
J 0
(-5015 3010);
DISPLAY 0.659574 (-5015 3010);
PAINT MONO (-5015 3010);
DISPLAY INVISIBLE (-5015 3010);
FORCEPROP 1 LAST HDL_POWER AGND_PVPP_ABC
J 1
(-5000 2875);
DISPLAY 0.617021 (-5000 2875);
PAINT GREEN (-5000 2875);
FORCEPROP 2 LAST BOM_COST PVPP_KLM_VR
J 0
(-5175 2900);
DISPLAY 1.042553 (-5175 2900);
PAINT WHITE (-5175 2900);
DISPLAY INVISIBLE (-5175 2900);
FORCEPROP 2 LAST ROOM PVPP_KLM_VR
J 0
(-5175 2900);
DISPLAY 1.042553 (-5175 2900);
PAINT GREEN (-5175 2900);
DISPLAY INVISIBLE (-5175 2900);
FORCEPROP 1 LAST VOLTAGE 0.0V
J 0
(-5070 2907);
DISPLAY 0.340426 (-5070 2907);
PAINT SKYBLUE (-5070 2907);
DISPLAY INVISIBLE (-5070 2907);
FORCEPROP 2 LAST CDS_LIB mstr_symbols
J 0
(-5025 2950);
PAINT MONO (-5025 2950);
DISPLAY INVISIBLE (-5025 2950);
FORCEPROP 1 LAST BODY_TYPE PLUMBING
J 0
(-5070 2907);
DISPLAY 0.340426 (-5070 2907);
PAINT GREEN (-5070 2907);
DISPLAY INVISIBLE (-5070 2907);
FORCEPROP 1 LAST PATH I204
J 0
(-4950 2950);
DISPLAY 0.872340 (-4950 2950);
PAINT AQUA (-4950 2950);
DISPLAY INVISIBLE (-4950 2950);
FORCEADD CAP_A..1
(-4775 3750);
FORCEPROP 1 LASTPIN (-4775 3650) $PN 2
J 0
(-4765 3630);
DISPLAY 0.617021 (-4765 3630);
PAINT ORANGE (-4765 3630);
FORCEPROP 1 LAST MATERIAL X7R
J 0
(-4725 3650);
DISPLAY 0.617021 (-4725 3650);
PAINT SKYBLUE (-4725 3650);
FORCEPROP 1 LAST VOLTAGE 16V
J 0
(-4725 3750);
DISPLAY 0.617021 (-4725 3750);
PAINT SKYBLUE (-4725 3750);
FORCEPROP 1 LAST TOLERANCE 10%
J 0
(-4725 3700);
DISPLAY 0.617021 (-4725 3700);
PAINT SKYBLUE (-4725 3700);
FORCEPROP 1 LASTPIN (-4775 3850) $PN 1
J 0
(-4765 3830);
DISPLAY 0.617021 (-4765 3830);
PAINT ORANGE (-4765 3830);
FORCEPROP 1 LAST LOCATION C7F6
J 0
(-4725 3850);
DISPLAY 0.617021 (-4725 3850);
PAINT AQUA (-4725 3850);
FORCEPROP 1 LAST PACK_TYPE 0402V
J 0
(-4725 3550);
DISPLAY 0.617021 (-4725 3550);
PAINT SKYBLUE (-4725 3550);
FORCEPROP 1 LAST VALUE 0.1UF
J 0
(-4725 3800);
DISPLAY 0.617021 (-4725 3800);
PAINT SKYBLUE (-4725 3800);
FORCEPROP 1 LAST PART_NUMBER A36096-030
J 0
(-4725 3600);
DISPLAY 0.617021 (-4725 3600);
PAINT BLUE (-4725 3600);
FORCEPROP 2 LAST CDS_LIB dev_discrete
J 0
(-4775 3750);
PAINT ORANGE (-4775 3750);
DISPLAY INVISIBLE (-4775 3750);
FORCEPROP 2 LAST SEC 1
J 0
(-4725 3950);
PAINT MONO (-4725 3950);
DISPLAY INVISIBLE (-4725 3950);
FORCEPROP 2 LAST SEC_TYPE 0402V
J 0
(-4725 3950);
DISPLAY 1.021277 (-4725 3950);
PAINT ORANGE (-4725 3950);
DISPLAY INVISIBLE (-4725 3950);
FORCEPROP 2 LAST CDS_SEC 1
J 0
(-4725 3900);
PAINT ORANGE (-4725 3900);
DISPLAY INVISIBLE (-4725 3900);
FORCEPROP 2 LAST CDS_LOCATION C7F6
J 0
(-4725 3850);
DISPLAY 0.617021 (-4725 3850);
PAINT AQUA (-4725 3850);
DISPLAY INVISIBLE (-4725 3850);
FORCEPROP 1 LAST PATH I205
J 0
(-4725 3900);
DISPLAY 0.978723 (-4725 3900);
PAINT WHITE (-4725 3900);
DISPLAY INVISIBLE (-4725 3900);
FORCEADD GND..1
(-4775 3525);
FORCEPROP 3 LASTPIN (-4775 3575) SIG_NAME GND\g
J 0
(-4765 3585);
DISPLAY 0.659574 (-4765 3585);
PAINT MONO (-4765 3585);
DISPLAY INVISIBLE (-4765 3585);
FORCEPROP 2 LAST ROOM PVPP_KLM_VR
J 0
(-5350 3600);
DISPLAY 1.042553 (-5350 3600);
PAINT GREEN (-5350 3600);
DISPLAY INVISIBLE (-5350 3600);
FORCEPROP 2 LAST BOM_COST PVPP_KLM_VR
J 0
(-5625 3600);
DISPLAY 1.042553 (-5625 3600);
PAINT WHITE (-5625 3600);
DISPLAY INVISIBLE (-5625 3600);
FORCEPROP 1 LAST PATH I206
J 0
(-4700 3525);
DISPLAY 0.872340 (-4700 3525);
PAINT AQUA (-4700 3525);
DISPLAY INVISIBLE (-4700 3525);
FORCEPROP 1 LAST BODY_TYPE PLUMBING
J 0
(-4820 3482);
DISPLAY 0.340426 (-4820 3482);
PAINT GREEN (-4820 3482);
DISPLAY INVISIBLE (-4820 3482);
FORCEPROP 2 LAST CDS_LIB mstr_symbols
J 0
(-4775 3525);
PAINT MONO (-4775 3525);
DISPLAY INVISIBLE (-4775 3525);
FORCEPROP 1 LAST SIZE 1B
J 0
(-4700 3475);
DISPLAY 0.872340 (-4700 3475);
PAINT GREEN (-4700 3475);
DISPLAY INVISIBLE (-4700 3475);
FORCEPROP 1 LAST VOLTAGE 0
J 0
(-4775 3525);
PAINT SKYBLUE (-4775 3525);
DISPLAY INVISIBLE (-4775 3525);
FORCEPROP 1 LAST HDL_POWER GND
J 0
(-4775 3675);
DISPLAY 0.872340 (-4775 3675);
PAINT GREEN (-4775 3675);
DISPLAY INVISIBLE (-4775 3675);
FORCEADD RES..1
(-3000 1225);
FORCEPROP 1 LASTPIN (-3100 1225) $PN 1
J 0
(-3088 1237);
DISPLAY 0.617021 (-3088 1237);
PAINT ORANGE (-3088 1237);
FORCEPROP 1 LAST WATTAGE 1/16W
J 2
(-3025 1075);
DISPLAY 0.617021 (-3025 1075);
PAINT SKYBLUE (-3025 1075);
FORCEPROP 1 LAST VALUE 22.1
J 2
(-3025 1125);
DISPLAY 0.617021 (-3025 1125);
PAINT SKYBLUE (-3025 1125);
FORCEPROP 1 LASTPIN (-2900 1225) $PN 2
J 0
(-2938 1237);
DISPLAY 0.617021 (-2938 1237);
PAINT ORANGE (-2938 1237);
FORCEPROP 1 LAST MATERIAL CHIP
J 0
(-3000 1075);
DISPLAY 0.617021 (-3000 1075);
PAINT SKYBLUE (-3000 1075);
FORCEPROP 1 LAST TOLERANCE 1.0%
J 0
(-3000 1125);
DISPLAY 0.617021 (-3000 1125);
PAINT SKYBLUE (-3000 1125);
FORCEPROP 1 LAST LOCATION R7F16
J 0
(-3050 1275);
DISPLAY 0.617021 (-3050 1275);
PAINT AQUA (-3050 1275);
FORCEPROP 1 LAST PART_NUMBER G21796-250
J 0
(-3050 1325);
DISPLAY 0.617021 (-3050 1325);
PAINT BLUE (-3050 1325);
FORCEPROP 1 LAST PACK_TYPE 0402
J 0
(-2750 1075);
DISPLAY 0.617021 (-2750 1075);
PAINT SKYBLUE (-2750 1075);
FORCEPROP 2 LAST CDS_LIB mstr_discrete
J 0
(-3000 1225);
PAINT MONO (-3000 1225);
DISPLAY INVISIBLE (-3000 1225);
FORCEPROP 2 LAST CDS_LOCATION R7F16
J 0
(-3050 1275);
DISPLAY 0.617021 (-3050 1275);
PAINT AQUA (-3050 1275);
DISPLAY INVISIBLE (-3050 1275);
FORCEPROP 2 LAST SEC 1
J 0
(-3050 1425);
DISPLAY 0.680851 (-3050 1425);
PAINT MONO (-3050 1425);
DISPLAY INVISIBLE (-3050 1425);
FORCEPROP 2 LAST SEC_TYPE 0402
J 0
(-3050 1425);
DISPLAY 1.021277 (-3050 1425);
PAINT ORANGE (-3050 1425);
DISPLAY INVISIBLE (-3050 1425);
FORCEPROP 1 LAST PATH I208
J 0
(-3050 1375);
DISPLAY 0.978723 (-3050 1375);
PAINT WHITE (-3050 1375);
DISPLAY INVISIBLE (-3050 1375);
FORCEPROP 2 LAST ROOM PVPP_KLM_VR
J 0
(-3050 1325);
DISPLAY 1.361702 (-3050 1325);
PAINT ORANGE (-3050 1325);
DISPLAY INVISIBLE (-3050 1325);
FORCEADD CAP..1
(-6300 4375);
FORCEPROP 1 LASTPIN (-6300 4275) $PN 2
J 0
(-6290 4255);
DISPLAY 0.617021 (-6290 4255);
PAINT ORANGE (-6290 4255);
FORCEPROP 1 LAST MATERIAL X6S
J 0
(-6250 4275);
DISPLAY 0.617021 (-6250 4275);
PAINT SKYBLUE (-6250 4275);
FORCEPROP 1 LAST TOLERANCE 10%
J 0
(-6250 4325);
DISPLAY 0.617021 (-6250 4325);
PAINT SKYBLUE (-6250 4325);
FORCEPROP 1 LASTPIN (-6300 4475) $PN 1
J 0
(-6290 4455);
DISPLAY 0.617021 (-6290 4455);
PAINT ORANGE (-6290 4455);
FORCEPROP 1 LAST VOLTAGE 16V
J 0
(-6250 4375);
DISPLAY 0.617021 (-6250 4375);
PAINT SKYBLUE (-6250 4375);
FORCEPROP 1 LAST PACK_TYPE 0805
J 0
(-6250 4175);
DISPLAY 0.617021 (-6250 4175);
PAINT SKYBLUE (-6250 4175);
FORCEPROP 1 LAST VALUE 10UF
J 0
(-6250 4425);
DISPLAY 0.617021 (-6250 4425);
PAINT SKYBLUE (-6250 4425);
FORCEPROP 1 LAST PART_NUMBER C95333-007
J 0
(-6250 4225);
DISPLAY 0.617021 (-6250 4225);
PAINT BLUE (-6250 4225);
FORCEPROP 1 LAST LOCATION C7F5
J 0
(-6250 4475);
DISPLAY 0.617021 (-6250 4475);
PAINT AQUA (-6250 4475);
FORCEPROP 2 LAST CDS_LIB mstr_discrete
J 0
(-6300 4375);
PAINT MONO (-6300 4375);
DISPLAY INVISIBLE (-6300 4375);
FORCEPROP 2 LAST SEC 1
J 0
(-6250 4575);
DISPLAY 0.680851 (-6250 4575);
PAINT MONO (-6250 4575);
DISPLAY INVISIBLE (-6250 4575);
FORCEPROP 2 LAST CDS_LOCATION C7F5
J 0
(-6250 4475);
DISPLAY 0.617021 (-6250 4475);
PAINT AQUA (-6250 4475);
DISPLAY INVISIBLE (-6250 4475);
FORCEPROP 1 LAST PATH I209
J 0
(-6250 4525);
DISPLAY 0.978723 (-6250 4525);
PAINT WHITE (-6250 4525);
DISPLAY INVISIBLE (-6250 4525);
FORCEPROP 2 LAST SEC_TYPE 0805
J 0
(-6250 4575);
DISPLAY 1.021277 (-6250 4575);
PAINT ORANGE (-6250 4575);
DISPLAY INVISIBLE (-6250 4575);
FORCEADD CAP..1
(-5900 4375);
FORCEPROP 1 LASTPIN (-5900 4475) $PN 1
J 0
(-5890 4455);
DISPLAY 0.617021 (-5890 4455);
PAINT ORANGE (-5890 4455);
FORCEPROP 1 LASTPIN (-5900 4275) $PN 2
J 0
(-5890 4255);
DISPLAY 0.617021 (-5890 4255);
PAINT ORANGE (-5890 4255);
FORCEPROP 1 LAST MATERIAL X6S
J 0
(-5850 4275);
DISPLAY 0.617021 (-5850 4275);
PAINT SKYBLUE (-5850 4275);
FORCEPROP 1 LAST VOLTAGE 16V
J 0
(-5850 4375);
DISPLAY 0.617021 (-5850 4375);
PAINT SKYBLUE (-5850 4375);
FORCEPROP 1 LAST PACK_TYPE 0805
J 0
(-5850 4175);
DISPLAY 0.617021 (-5850 4175);
PAINT SKYBLUE (-5850 4175);
FORCEPROP 1 LAST TOLERANCE 10%
J 0
(-5850 4325);
DISPLAY 0.617021 (-5850 4325);
PAINT SKYBLUE (-5850 4325);
FORCEPROP 1 LAST VALUE 10UF
J 0
(-5850 4425);
DISPLAY 0.617021 (-5850 4425);
PAINT SKYBLUE (-5850 4425);
FORCEPROP 1 LAST LOCATION C3T8
J 0
(-5850 4475);
DISPLAY 0.617021 (-5850 4475);
PAINT AQUA (-5850 4475);
FORCEPROP 1 LAST PART_NUMBER C95333-007
J 0
(-5850 4225);
DISPLAY 0.617021 (-5850 4225);
PAINT BLUE (-5850 4225);
FORCEPROP 2 LAST CDS_LIB mstr_discrete
J 0
(-5900 4375);
PAINT MONO (-5900 4375);
DISPLAY INVISIBLE (-5900 4375);
FORCEPROP 1 LAST PATH I210
J 0
(-5850 4525);
DISPLAY 0.978723 (-5850 4525);
PAINT WHITE (-5850 4525);
DISPLAY INVISIBLE (-5850 4525);
FORCEPROP 2 LAST CDS_LOCATION C3T8
J 0
(-5850 4475);
DISPLAY 0.617021 (-5850 4475);
PAINT AQUA (-5850 4475);
DISPLAY INVISIBLE (-5850 4475);
FORCEPROP 2 LAST SEC 1
J 0
(-5850 4575);
DISPLAY 0.680851 (-5850 4575);
PAINT MONO (-5850 4575);
DISPLAY INVISIBLE (-5850 4575);
FORCEPROP 2 LAST SEC_TYPE 0805
J 0
(-5850 4575);
DISPLAY 1.021277 (-5850 4575);
PAINT ORANGE (-5850 4575);
DISPLAY INVISIBLE (-5850 4575);
FORCEADD CAP..1
(-5500 4375);
FORCEPROP 1 LASTPIN (-5500 4275) $PN 2
J 0
(-5490 4255);
DISPLAY 0.617021 (-5490 4255);
PAINT ORANGE (-5490 4255);
FORCEPROP 1 LASTPIN (-5500 4475) $PN 1
J 0
(-5490 4455);
DISPLAY 0.617021 (-5490 4455);
PAINT ORANGE (-5490 4455);
FORCEPROP 1 LAST MATERIAL X6S
J 0
(-5450 4275);
DISPLAY 0.617021 (-5450 4275);
PAINT SKYBLUE (-5450 4275);
FORCEPROP 1 LAST VOLTAGE 16V
J 0
(-5450 4375);
DISPLAY 0.617021 (-5450 4375);
PAINT SKYBLUE (-5450 4375);
FORCEPROP 1 LAST PACK_TYPE 0805
J 0
(-5450 4175);
DISPLAY 0.617021 (-5450 4175);
PAINT SKYBLUE (-5450 4175);
FORCEPROP 1 LAST TOLERANCE 10%
J 0
(-5450 4325);
DISPLAY 0.617021 (-5450 4325);
PAINT SKYBLUE (-5450 4325);
FORCEPROP 1 LAST VALUE 10UF
J 0
(-5450 4425);
DISPLAY 0.617021 (-5450 4425);
PAINT SKYBLUE (-5450 4425);
FORCEPROP 1 LAST PART_NUMBER C95333-007
J 0
(-5450 4225);
DISPLAY 0.617021 (-5450 4225);
PAINT BLUE (-5450 4225);
FORCEPROP 1 LAST LOCATION C3T14
J 0
(-5450 4475);
DISPLAY 0.617021 (-5450 4475);
PAINT AQUA (-5450 4475);
FORCEPROP 2 LAST CDS_LIB mstr_discrete
J 0
(-5500 4375);
PAINT MONO (-5500 4375);
DISPLAY INVISIBLE (-5500 4375);
FORCEPROP 2 LAST SEC 1
J 0
(-5450 4575);
DISPLAY 0.680851 (-5450 4575);
PAINT MONO (-5450 4575);
DISPLAY INVISIBLE (-5450 4575);
FORCEPROP 2 LAST CDS_LOCATION C3T14
J 0
(-5450 4475);
DISPLAY 0.617021 (-5450 4475);
PAINT AQUA (-5450 4475);
DISPLAY INVISIBLE (-5450 4475);
FORCEPROP 1 LAST PATH I211
J 0
(-5450 4525);
DISPLAY 0.978723 (-5450 4525);
PAINT WHITE (-5450 4525);
DISPLAY INVISIBLE (-5450 4525);
FORCEPROP 2 LAST SEC_TYPE 0805
J 0
(-5450 4575);
DISPLAY 1.021277 (-5450 4575);
PAINT ORANGE (-5450 4575);
DISPLAY INVISIBLE (-5450 4575);
FORCEADD GND..1
(-5500 4175);
FORCEPROP 3 LASTPIN (-5500 4225) SIG_NAME GND\g
J 0
(-5490 4235);
DISPLAY 0.659574 (-5490 4235);
PAINT MONO (-5490 4235);
DISPLAY INVISIBLE (-5490 4235);
FORCEPROP 2 LAST BOM_COST PVPP_KLM_VR
J 0
(-6350 4250);
DISPLAY 1.042553 (-6350 4250);
PAINT WHITE (-6350 4250);
DISPLAY INVISIBLE (-6350 4250);
FORCEPROP 2 LAST ROOM PVPP_KLM_VR
J 0
(-6075 4250);
DISPLAY 1.042553 (-6075 4250);
PAINT GREEN (-6075 4250);
DISPLAY INVISIBLE (-6075 4250);
FORCEPROP 1 LAST BODY_TYPE PLUMBING
J 0
(-5545 4132);
DISPLAY 0.340426 (-5545 4132);
PAINT GREEN (-5545 4132);
DISPLAY INVISIBLE (-5545 4132);
FORCEPROP 1 LAST VOLTAGE 0
J 0
(-5500 4175);
PAINT SKYBLUE (-5500 4175);
DISPLAY INVISIBLE (-5500 4175);
FORCEPROP 1 LAST SIZE 1B
J 0
(-5425 4125);
DISPLAY 0.872340 (-5425 4125);
PAINT GREEN (-5425 4125);
DISPLAY INVISIBLE (-5425 4125);
FORCEPROP 2 LAST CDS_LIB mstr_symbols
J 0
(-5500 4175);
PAINT MONO (-5500 4175);
DISPLAY INVISIBLE (-5500 4175);
FORCEPROP 1 LAST PATH I212
J 0
(-5425 4175);
DISPLAY 0.872340 (-5425 4175);
PAINT AQUA (-5425 4175);
DISPLAY INVISIBLE (-5425 4175);
FORCEPROP 1 LAST HDL_POWER GND
J 0
(-5500 4325);
DISPLAY 0.872340 (-5500 4325);
PAINT GREEN (-5500 4325);
DISPLAY INVISIBLE (-5500 4325);
FORCEADD GND..1
(-5900 4175);
FORCEPROP 3 LASTPIN (-5900 4225) SIG_NAME GND\g
J 0
(-5890 4235);
DISPLAY 0.659574 (-5890 4235);
PAINT MONO (-5890 4235);
DISPLAY INVISIBLE (-5890 4235);
FORCEPROP 2 LAST BOM_COST PVPP_KLM_VR
J 0
(-6750 4250);
DISPLAY 1.042553 (-6750 4250);
PAINT WHITE (-6750 4250);
DISPLAY INVISIBLE (-6750 4250);
FORCEPROP 2 LAST ROOM PVPP_KLM_VR
J 0
(-6475 4250);
DISPLAY 1.042553 (-6475 4250);
PAINT GREEN (-6475 4250);
DISPLAY INVISIBLE (-6475 4250);
FORCEPROP 1 LAST VOLTAGE 0
J 0
(-5900 4175);
PAINT SKYBLUE (-5900 4175);
DISPLAY INVISIBLE (-5900 4175);
FORCEPROP 2 LAST CDS_LIB mstr_symbols
J 0
(-5900 4175);
PAINT MONO (-5900 4175);
DISPLAY INVISIBLE (-5900 4175);
FORCEPROP 1 LAST BODY_TYPE PLUMBING
J 0
(-5945 4132);
DISPLAY 0.340426 (-5945 4132);
PAINT GREEN (-5945 4132);
DISPLAY INVISIBLE (-5945 4132);
FORCEPROP 1 LAST HDL_POWER GND
J 0
(-5900 4325);
DISPLAY 0.872340 (-5900 4325);
PAINT GREEN (-5900 4325);
DISPLAY INVISIBLE (-5900 4325);
FORCEPROP 1 LAST PATH I213
J 0
(-5825 4175);
DISPLAY 0.872340 (-5825 4175);
PAINT AQUA (-5825 4175);
DISPLAY INVISIBLE (-5825 4175);
FORCEPROP 1 LAST SIZE 1B
J 0
(-5825 4125);
DISPLAY 0.872340 (-5825 4125);
PAINT GREEN (-5825 4125);
DISPLAY INVISIBLE (-5825 4125);
FORCEADD GND..1
(-6300 4175);
FORCEPROP 3 LASTPIN (-6300 4225) SIG_NAME GND\g
J 0
(-6290 4235);
DISPLAY 0.659574 (-6290 4235);
PAINT MONO (-6290 4235);
DISPLAY INVISIBLE (-6290 4235);
FORCEPROP 2 LAST BOM_COST PVPP_KLM_VR
J 0
(-7150 4250);
DISPLAY 1.042553 (-7150 4250);
PAINT WHITE (-7150 4250);
DISPLAY INVISIBLE (-7150 4250);
FORCEPROP 2 LAST ROOM PVPP_KLM_VR
J 0
(-6875 4250);
DISPLAY 1.042553 (-6875 4250);
PAINT GREEN (-6875 4250);
DISPLAY INVISIBLE (-6875 4250);
FORCEPROP 1 LAST VOLTAGE 0
J 0
(-6300 4175);
PAINT SKYBLUE (-6300 4175);
DISPLAY INVISIBLE (-6300 4175);
FORCEPROP 2 LAST CDS_LIB mstr_symbols
J 0
(-6300 4175);
PAINT MONO (-6300 4175);
DISPLAY INVISIBLE (-6300 4175);
FORCEPROP 1 LAST BODY_TYPE PLUMBING
J 0
(-6345 4132);
DISPLAY 0.340426 (-6345 4132);
PAINT GREEN (-6345 4132);
DISPLAY INVISIBLE (-6345 4132);
FORCEPROP 1 LAST SIZE 1B
J 0
(-6225 4125);
DISPLAY 0.872340 (-6225 4125);
PAINT GREEN (-6225 4125);
DISPLAY INVISIBLE (-6225 4125);
FORCEPROP 1 LAST PATH I214
J 0
(-6225 4175);
DISPLAY 0.872340 (-6225 4175);
PAINT AQUA (-6225 4175);
DISPLAY INVISIBLE (-6225 4175);
FORCEPROP 1 LAST HDL_POWER GND
J 0
(-6300 4325);
DISPLAY 0.872340 (-6300 4325);
PAINT GREEN (-6300 4325);
DISPLAY INVISIBLE (-6300 4325);
FORCEADD CAP..1
(-5075 4375);
FORCEPROP 1 LASTPIN (-5075 4275) $PN 2
J 0
(-5065 4255);
DISPLAY 0.617021 (-5065 4255);
PAINT ORANGE (-5065 4255);
FORCEPROP 1 LAST TOLERANCE 10%
J 0
(-5025 4325);
DISPLAY 0.617021 (-5025 4325);
PAINT SKYBLUE (-5025 4325);
FORCEPROP 1 LAST PACK_TYPE 0805
J 0
(-5025 4175);
DISPLAY 0.617021 (-5025 4175);
PAINT SKYBLUE (-5025 4175);
FORCEPROP 1 LAST MATERIAL X6S
J 0
(-5025 4275);
DISPLAY 0.617021 (-5025 4275);
PAINT SKYBLUE (-5025 4275);
FORCEPROP 1 LASTPIN (-5075 4475) $PN 1
J 0
(-5065 4455);
DISPLAY 0.617021 (-5065 4455);
PAINT ORANGE (-5065 4455);
FORCEPROP 1 LAST LOCATION C3T12
J 0
(-5025 4475);
DISPLAY 0.617021 (-5025 4475);
PAINT AQUA (-5025 4475);
FORCEPROP 1 LAST VALUE 10UF
J 0
(-5025 4425);
DISPLAY 0.617021 (-5025 4425);
PAINT SKYBLUE (-5025 4425);
FORCEPROP 1 LAST VOLTAGE 16V
J 0
(-5025 4375);
DISPLAY 0.617021 (-5025 4375);
PAINT SKYBLUE (-5025 4375);
FORCEPROP 1 LAST PART_NUMBER C95333-007
J 0
(-5025 4225);
DISPLAY 0.617021 (-5025 4225);
PAINT BLUE (-5025 4225);
FORCEPROP 2 LAST CDS_LIB mstr_discrete
J 0
(-5075 4375);
PAINT MONO (-5075 4375);
DISPLAY INVISIBLE (-5075 4375);
FORCEPROP 2 LAST CDS_LOCATION C3T12
J 0
(-5025 4475);
DISPLAY 0.617021 (-5025 4475);
PAINT AQUA (-5025 4475);
DISPLAY INVISIBLE (-5025 4475);
FORCEPROP 1 LAST PATH I215
J 0
(-5025 4525);
DISPLAY 0.978723 (-5025 4525);
PAINT WHITE (-5025 4525);
DISPLAY INVISIBLE (-5025 4525);
FORCEPROP 2 LAST SEC 1
J 0
(-5025 4575);
DISPLAY 0.680851 (-5025 4575);
PAINT MONO (-5025 4575);
DISPLAY INVISIBLE (-5025 4575);
FORCEPROP 2 LAST SEC_TYPE 0805
J 0
(-5025 4575);
DISPLAY 1.021277 (-5025 4575);
PAINT ORANGE (-5025 4575);
DISPLAY INVISIBLE (-5025 4575);
FORCEADD GND..1
(-5075 4175);
FORCEPROP 3 LASTPIN (-5075 4225) SIG_NAME GND\g
J 0
(-5065 4235);
DISPLAY 0.659574 (-5065 4235);
PAINT MONO (-5065 4235);
DISPLAY INVISIBLE (-5065 4235);
FORCEPROP 2 LAST BOM_COST PVPP_KLM_VR
J 0
(-5925 4250);
DISPLAY 1.042553 (-5925 4250);
PAINT WHITE (-5925 4250);
DISPLAY INVISIBLE (-5925 4250);
FORCEPROP 2 LAST ROOM PVPP_KLM_VR
J 0
(-5650 4250);
DISPLAY 1.042553 (-5650 4250);
PAINT GREEN (-5650 4250);
DISPLAY INVISIBLE (-5650 4250);
FORCEPROP 1 LAST BODY_TYPE PLUMBING
J 0
(-5120 4132);
DISPLAY 0.340426 (-5120 4132);
PAINT GREEN (-5120 4132);
DISPLAY INVISIBLE (-5120 4132);
FORCEPROP 1 LAST PATH I216
J 0
(-5000 4175);
DISPLAY 0.872340 (-5000 4175);
PAINT AQUA (-5000 4175);
DISPLAY INVISIBLE (-5000 4175);
FORCEPROP 2 LAST CDS_LIB mstr_symbols
J 0
(-5075 4175);
PAINT MONO (-5075 4175);
DISPLAY INVISIBLE (-5075 4175);
FORCEPROP 1 LAST SIZE 1B
J 0
(-5000 4125);
DISPLAY 0.872340 (-5000 4125);
PAINT GREEN (-5000 4125);
DISPLAY INVISIBLE (-5000 4125);
FORCEPROP 1 LAST VOLTAGE 0
J 0
(-5075 4175);
PAINT SKYBLUE (-5075 4175);
DISPLAY INVISIBLE (-5075 4175);
FORCEPROP 1 LAST HDL_POWER GND
J 0
(-5075 4325);
DISPLAY 0.872340 (-5075 4325);
PAINT GREEN (-5075 4325);
DISPLAY INVISIBLE (-5075 4325);
FORCEADD CAPP..1
(-1075 3875);
FORCEPROP 1 LASTPIN (-1075 3775) $PN 2
J 0
(-1065 3760);
DISPLAY 0.617021 (-1065 3760);
PAINT ORANGE (-1065 3760);
FORCEPROP 1 LASTPIN (-1075 3975) $PN 1
J 0
(-1065 3960);
DISPLAY 0.617021 (-1065 3960);
PAINT ORANGE (-1065 3960);
FORCEPROP 1 LAST MATERIAL POSCAP
J 0
(-1025 3775);
DISPLAY 0.617021 (-1025 3775);
PAINT SKYBLUE (-1025 3775);
FORCEPROP 1 LAST VOLTAGE 4V
J 0
(-1025 3825);
DISPLAY 0.617021 (-1025 3825);
PAINT SKYBLUE (-1025 3825);
FORCEPROP 1 LAST PACK_TYPE 7343
J 0
(-1025 3725);
DISPLAY 0.617021 (-1025 3725);
PAINT SKYBLUE (-1025 3725);
FORCEPROP 1 LAST TOLERANCE 20%
J 0
(-1025 3875);
DISPLAY 0.617021 (-1025 3875);
PAINT SKYBLUE (-1025 3875);
FORCEPROP 1 LAST VALUE 220UF
J 0
(-1025 3925);
DISPLAY 0.617021 (-1025 3925);
PAINT SKYBLUE (-1025 3925);
FORCEPROP 1 LAST PART_NUMBER 724613-067
J 0
(-1025 3675);
DISPLAY 0.617021 (-1025 3675);
PAINT BLUE (-1025 3675);
FORCEPROP 1 LAST LOCATION C4T3
J 0
(-1025 3975);
DISPLAY 0.617021 (-1025 3975);
PAINT AQUA (-1025 3975);
FORCEPROP 2 LAST CDS_LIB mstr_discrete
J 0
(-1075 3875);
PAINT ORANGE (-1075 3875);
DISPLAY INVISIBLE (-1075 3875);
FORCEPROP 1 LAST PATH I217
J 0
(-1025 4025);
DISPLAY 0.978723 (-1025 4025);
PAINT ORANGE (-1025 4025);
DISPLAY INVISIBLE (-1025 4025);
FORCEPROP 2 LAST CDS_LOCATION C4T3
J 0
(-1025 3975);
DISPLAY 0.617021 (-1025 3975);
PAINT AQUA (-1025 3975);
DISPLAY INVISIBLE (-1025 3975);
FORCEPROP 2 LAST SEC 1
J 0
(-1025 4075);
DISPLAY 0.680851 (-1025 4075);
PAINT MONO (-1025 4075);
DISPLAY INVISIBLE (-1025 4075);
FORCEPROP 2 LAST SEC_TYPE 7343
J 0
(-1025 4075);
DISPLAY 1.021277 (-1025 4075);
PAINT ORANGE (-1025 4075);
DISPLAY INVISIBLE (-1025 4075);
FORCEADD RES..2
(-675 2875);
FORCEPROP 1 LASTPIN (-675 2775) $PN 2
J 0
(-670 2785);
DISPLAY 0.617021 (-670 2785);
PAINT ORANGE (-670 2785);
FORCEPROP 1 LAST MATERIAL CHIP
J 0
(-635 2750);
DISPLAY 0.617021 (-635 2750);
PAINT SKYBLUE (-635 2750);
FORCEPROP 1 LAST PACK_TYPE 0402
J 0
(-635 2800);
DISPLAY 0.617021 (-635 2800);
PAINT SKYBLUE (-635 2800);
FORCEPROP 1 LASTPIN (-675 2975) $PN 1
J 0
(-670 2937);
DISPLAY 0.617021 (-670 2937);
PAINT ORANGE (-670 2937);
FORCEPROP 1 LAST VALUE 1.0K
J 0
(-630 2950);
DISPLAY 0.617021 (-630 2950);
PAINT SKYBLUE (-630 2950);
FORCEPROP 1 LAST TOLERANCE 0.1%
J 0
(-630 2900);
DISPLAY 0.617021 (-630 2900);
PAINT SKYBLUE (-630 2900);
FORCEPROP 1 LAST WATTAGE 1/16W
J 0
(-635 2850);
DISPLAY 0.617021 (-635 2850);
PAINT SKYBLUE (-635 2850);
FORCEPROP 1 LAST PART_NUMBER G85996-004
J 0
(-660 2700);
DISPLAY 0.617021 (-660 2700);
PAINT BLUE (-660 2700);
FORCEPROP 1 LAST LOCATION R7F17
J 0
(-630 3000);
DISPLAY 0.617021 (-630 3000);
PAINT AQUA (-630 3000);
FORCEPROP 2 LAST CDS_LIB mstr_discrete
J 0
(-675 2875);
PAINT MONO (-675 2875);
DISPLAY INVISIBLE (-675 2875);
FORCEPROP 2 LAST CDS_LOCATION R7F17
J 0
(-630 3000);
DISPLAY 0.617021 (-630 3000);
PAINT AQUA (-630 3000);
DISPLAY INVISIBLE (-630 3000);
FORCEPROP 2 LAST ROOM PVPP_KLM_VR
J 0
(-630 3030);
PAINT GREEN (-630 3030);
DISPLAY INVISIBLE (-630 3030);
FORCEPROP 1 LAST PATH I218
J 0
(-625 3050);
DISPLAY 0.978723 (-625 3050);
PAINT WHITE (-625 3050);
DISPLAY INVISIBLE (-625 3050);
FORCEPROP 2 LAST BOM_COST PVPP_KLM_VR
J 0
(-630 3055);
DISPLAY 1.042553 (-630 3055);
PAINT WHITE (-630 3055);
DISPLAY INVISIBLE (-630 3055);
FORCEPROP 0 LAST SPOF TRUE
J 0
(-625 3100);
DISPLAY 1.021277 (-625 3100);
PAINT ORANGE (-625 3100);
DISPLAY INVISIBLE (-625 3100);
FORCEPROP 2 LAST SEC_TYPE 0402
J 0
(-625 3100);
DISPLAY 1.021277 (-625 3100);
PAINT ORANGE (-625 3100);
DISPLAY INVISIBLE (-625 3100);
FORCEPROP 2 LAST REUSE_ID 9
J 0
(-625 3100);
DISPLAY 1.042553 (-625 3100);
PAINT ORANGE (-625 3100);
DISPLAY INVISIBLE (-625 3100);
FORCEPROP 2 LAST SEC 1
J 0
(-625 3100);
DISPLAY 0.680851 (-625 3100);
PAINT MONO (-625 3100);
DISPLAY INVISIBLE (-625 3100);
FORCEADD CAP..1
(-675 2325);
FORCEPROP 1 LASTPIN (-675 2225) $PN 2
J 0
(-665 2205);
DISPLAY 0.617021 (-665 2205);
PAINT ORANGE (-665 2205);
FORCEPROP 1 LAST MATERIAL X7R
J 0
(-625 2225);
DISPLAY 0.617021 (-625 2225);
PAINT SKYBLUE (-625 2225);
FORCEPROP 1 LAST TOLERANCE 10%
J 0
(-625 2275);
DISPLAY 0.617021 (-625 2275);
PAINT SKYBLUE (-625 2275);
FORCEPROP 1 LAST VOLTAGE 50V
J 0
(-625 2325);
DISPLAY 0.617021 (-625 2325);
PAINT SKYBLUE (-625 2325);
FORCEPROP 1 LASTPIN (-675 2425) $PN 1
J 0
(-665 2405);
DISPLAY 0.617021 (-665 2405);
PAINT ORANGE (-665 2405);
FORCEPROP 1 LAST PACK_TYPE 0402LF
J 0
(-625 2125);
DISPLAY 0.617021 (-625 2125);
PAINT SKYBLUE (-625 2125);
FORCEPROP 1 LAST VALUE 2200PF
J 0
(-625 2375);
DISPLAY 0.617021 (-625 2375);
PAINT SKYBLUE (-625 2375);
FORCEPROP 1 LAST PART_NUMBER A36096-075
J 0
(-625 2175);
DISPLAY 0.617021 (-625 2175);
PAINT BLUE (-625 2175);
FORCEPROP 1 LAST LOCATION C7F13
J 0
(-625 2425);
DISPLAY 0.617021 (-625 2425);
PAINT AQUA (-625 2425);
FORCEPROP 2 LAST BOM_COST PVPP_KLM_VR
J 0
(-625 2475);
DISPLAY 1.042553 (-625 2475);
PAINT WHITE (-625 2475);
DISPLAY INVISIBLE (-625 2475);
FORCEPROP 2 LAST CDS_LIB mstr_discrete
J 0
(-675 2325);
PAINT ORANGE (-675 2325);
DISPLAY INVISIBLE (-675 2325);
FORCEPROP 2 LAST SEC 1
J 0
(-625 2525);
DISPLAY 0.680851 (-625 2525);
PAINT MONO (-625 2525);
DISPLAY INVISIBLE (-625 2525);
FORCEPROP 2 LAST CDS_LOCATION C7F13
J 0
(-625 2425);
DISPLAY 0.617021 (-625 2425);
PAINT AQUA (-625 2425);
DISPLAY INVISIBLE (-625 2425);
FORCEPROP 1 LAST PATH I219
J 0
(-625 2475);
DISPLAY 0.978723 (-625 2475);
PAINT WHITE (-625 2475);
DISPLAY INVISIBLE (-625 2475);
FORCEPROP 2 LAST ROOM PVPP_KLM_VR
J 0
(-625 2450);
PAINT GREEN (-625 2450);
DISPLAY INVISIBLE (-625 2450);
FORCEPROP 2 LAST REUSE_ID 26
J 0
(-625 2525);
DISPLAY 1.042553 (-625 2525);
PAINT ORANGE (-625 2525);
DISPLAY INVISIBLE (-625 2525);
FORCEPROP 0 LAST SPOF TRUE
J 0
(-625 2525);
DISPLAY 1.021277 (-625 2525);
PAINT ORANGE (-625 2525);
DISPLAY INVISIBLE (-625 2525);
FORCEPROP 2 LAST SEC_TYPE 0402LF
J 0
(-625 2525);
DISPLAY 1.021277 (-625 2525);
PAINT ORANGE (-625 2525);
DISPLAY INVISIBLE (-625 2525);
FORCEADD RES..1
(-5775 3075);
FORCEPROP 1 LAST WATTAGE 1/16W
J 2
(-5800 2925);
DISPLAY 0.617021 (-5800 2925);
PAINT SKYBLUE (-5800 2925);
FORCEPROP 1 LAST VALUE 0.0
J 2
(-5875 2975);
DISPLAY 0.617021 (-5875 2975);
PAINT SKYBLUE (-5875 2975);
FORCEPROP 1 LAST PART_NUMBER G21497-005
J 0
(-5925 3025);
DISPLAY 0.617021 (-5925 3025);
PAINT BLUE (-5925 3025);
FORCEPROP 1 LAST MATERIAL CHIP
J 0
(-5775 2925);
DISPLAY 0.617021 (-5775 2925);
PAINT SKYBLUE (-5775 2925);
FORCEPROP 1 LAST TOLERANCE 5%
J 0
(-5825 2975);
DISPLAY 0.617021 (-5825 2975);
PAINT SKYBLUE (-5825 2975);
FORCEPROP 1 LAST PACK_TYPE 0402
J 0
(-5700 2975);
DISPLAY 0.617021 (-5700 2975);
PAINT SKYBLUE (-5700 2975);
FORCEPROP 1 LASTPIN (-5875 3075) $PN 1
J 0
(-5863 3087);
DISPLAY 0.617021 (-5863 3087);
PAINT ORANGE (-5863 3087);
FORCEPROP 1 LAST LOCATION R7F9
J 0
(-5825 3125);
DISPLAY 0.617021 (-5825 3125);
PAINT AQUA (-5825 3125);
FORCEPROP 1 LASTPIN (-5675 3075) $PN 2
J 0
(-5713 3087);
DISPLAY 0.617021 (-5713 3087);
PAINT ORANGE (-5713 3087);
FORCEPROP 2 LAST CDS_LIB mstr_discrete
J 0
(-5775 3075);
PAINT ORANGE (-5775 3075);
DISPLAY INVISIBLE (-5775 3075);
FORCEPROP 2 LAST SEC_TYPE 0402
J 0
(-5825 3275);
DISPLAY 1.021277 (-5825 3275);
PAINT ORANGE (-5825 3275);
DISPLAY INVISIBLE (-5825 3275);
FORCEPROP 2 LAST SEC 1
J 0
(-5825 3275);
PAINT MONO (-5825 3275);
DISPLAY INVISIBLE (-5825 3275);
FORCEPROP 2 LAST CDS_LOCATION R7F9
J 0
(-5825 3125);
DISPLAY 0.617021 (-5825 3125);
PAINT AQUA (-5825 3125);
DISPLAY INVISIBLE (-5825 3125);
FORCEPROP 1 LAST PATH I220
J 0
(-5825 3225);
DISPLAY 0.978723 (-5825 3225);
PAINT WHITE (-5825 3225);
DISPLAY INVISIBLE (-5825 3225);
FORCEPROP 2 LAST ROOM PVCCIN_CPU0_VR
J 0
(-5825 3175);
DISPLAY 1.361702 (-5825 3175);
PAINT ORANGE (-5825 3175);
DISPLAY INVISIBLE (-5825 3175);
FORCEADD DNS..2
(-6170 2645);
PAINT RED (-6170 2645);
FORCEPROP 1 LAST COMMENT_BODY TRUE
R 1
J 0
(-6095 2420);
DISPLAY 0.872340 (-6095 2420);
PAINT GREEN (-6095 2420);
DISPLAY INVISIBLE (-6095 2420);
FORCEPROP 2 LAST CDS_LIB mstr_misc
J 0
(-6170 2645);
PAINT ORANGE (-6170 2645);
DISPLAY INVISIBLE (-6170 2645);
FORCEADD DNS..2
(-2295 3595);
PAINT RED (-2295 3595);
FORCEPROP 1 LAST COMMENT_BODY TRUE
R 1
J 0
(-2220 3370);
DISPLAY 0.872340 (-2220 3370);
PAINT GREEN (-2220 3370);
DISPLAY INVISIBLE (-2220 3370);
FORCEPROP 2 LAST CDS_LIB mstr_misc
J 0
(-2295 3595);
PAINT ORANGE (-2295 3595);
DISPLAY INVISIBLE (-2295 3595);
FORCEADD DNS..2
(-2295 3945);
PAINT RED (-2295 3945);
FORCEPROP 1 LAST COMMENT_BODY TRUE
R 1
J 0
(-2220 3720);
DISPLAY 0.872340 (-2220 3720);
PAINT GREEN (-2220 3720);
DISPLAY INVISIBLE (-2220 3720);
FORCEPROP 2 LAST CDS_LIB mstr_misc
J 0
(-2295 3945);
PAINT ORANGE (-2295 3945);
DISPLAY INVISIBLE (-2295 3945);
FORCEADD CAD_NOTE..1
(-6125 5075);
FORCEPROP 0 LAST LINE PLACE DECOUPLING SAME SIDE
J 0
(-6350 4825);
DISPLAY 0.787234 (-6350 4825);
PAINT WHITE (-6350 4825);
FORCEPROP 0 LAST LINE2 AND CLOSE TO IC PINS
J 0
(-6275 4875);
DISPLAY 0.787234 (-6275 4875);
PAINT WHITE (-6275 4875);
FORCEPROP 2 LAST ROOM PVPP_KLM_VR
J 0
(-6275 5000);
DISPLAY 1.042553 (-6275 5000);
PAINT GREEN (-6275 5000);
DISPLAY INVISIBLE (-6275 5000);
FORCEPROP 2 LAST BOM_COST PVPP_KLM_VR
J 0
(-6275 5050);
DISPLAY 1.042553 (-6275 5050);
PAINT WHITE (-6275 5050);
DISPLAY INVISIBLE (-6275 5050);
FORCEPROP 2 LAST CDS_LIB mstr_symbols
J 0
(-6125 5075);
PAINT MONO (-6125 5075);
DISPLAY INVISIBLE (-6125 5075);
FORCEPROP 1 LAST COMMENT_BODY TRUE
J 0
(-6100 5175);
PAINT PEACH (-6100 5175);
DISPLAY INVISIBLE (-6100 5175);
FORCEADD INTEL_CORP_BPAGE..1
(-125 50);
FORCEPROP 1 LAST CDS_CON_LAST_MODIFIED Tue Dec 01 11:52:29 2015
J 0
(-1550 375);
DISPLAY 0.659574 (-1550 375);
PAINT GREEN (-1550 375);
DISPLAY INVISIBLE (-1550 375);
FORCEPROP 1 LAST CUSTOM_TXT_CDS <CURRENT_DESIGN_SHEET> OF <TOTAL_DESIGN_SHEETS>
J 0
(-625 75);
PAINT GREEN (-625 75);
FORCEPROP 2 LAST CUSTOM_TXT_CDS <XR_PAGE_TITLE>
J 0
(-8015 5300);
DISPLAY 0.638298 (-8015 5300);
PAINT PINK (-8015 5300);
DISPLAY INVISIBLE (-8015 5300);
FORCEPROP 2 LAST CUSTOM_TXT_CDS <CON_LAST_MODIFIED>
J 0
(-2050 400);
DISPLAY 0.957447 (-2050 400);
PAINT ORANGE (-2050 400);
FORCEPROP 1 LAST SCH_TITLE VPP ABC VR
J 0
(-8075 100);
DISPLAY 1.212766 (-8075 100);
PAINT GREEN (-8075 100);
FORCEPROP 1 LAST SCH_ADDRESS1 2200 Mission College Blvd.
J 0
(-4100 175);
DISPLAY 0.617021 (-4100 175);
PAINT GREEN (-4100 175);
FORCEPROP 1 LAST SCH_ADDRESS2 P.O. BOX 58119
J 0
(-4100 125);
DISPLAY 0.617021 (-4100 125);
PAINT GREEN (-4100 125);
FORCEPROP 1 LAST SCH_ADDRESS3 Santa Clara, CA 95052-8119
J 0
(-4100 75);
DISPLAY 0.617021 (-4100 75);
PAINT GREEN (-4100 75);
FORCEPROP 1 LAST SCH_NUMBER H4694802
J 0
(-1425 200);
DISPLAY 1.212766 (-1425 200);
PAINT YELLOW (-1425 200);
FORCEPROP 1 LAST SCH_DEPT BESD
J 1
(-4575 150);
DISPLAY 1.212766 (-4575 150);
PAINT YELLOW (-4575 150);
FORCEPROP 1 LAST SCH_REV 2.420
J 0
(-375 200);
DISPLAY 0.978723 (-375 200);
PAINT YELLOW (-375 200);
FORCEPROP 2 LAST PAGE_BORDER TRUE
J 0
(-8015 5300);
DISPLAY 0.425532 (-8015 5300);
PAINT PINK (-8015 5300);
DISPLAY INVISIBLE (-8015 5300);
FORCEPROP 1 LAST COMMENT_BODY TRUE
J 0
(-113 62);
DISPLAY 0.319149 (-113 62);
PAINT GREEN (-113 62);
DISPLAY INVISIBLE (-113 62);
FORCEPROP 2 LAST CDS_LIB mstr_symbols
J 0
(-125 50);
DISPLAY 0.489362 (-125 50);
PAINT ORANGE (-125 50);
DISPLAY INVISIBLE (-125 50);
FORCEPROP 2 LAST CDS_XR_PAGE_TITLE CR-231 : @BASEBOARD_FAB2_LIB.BASEBOARD_FAB2(SCH_1):PAGE231
J 0
(-8015 5300);
DISPLAY 0.638298 (-8015 5300);
PAINT PINK (-8015 5300);
DISPLAY INVISIBLE (-8015 5300);
WIRE 16 -1 (-4825 1100)(-4825 1175);
WIRE 16 -1 (-4825 1175)(-5075 1175);
WIRE 16 -1 (-5075 1075)(-5075 1175);
WIRE 16 -1 (-5075 1175)(-5350 1175);
WIRE 16 -1 (-5350 1075)(-5350 1175);
WIRE 16 -1 (-5350 1175)(-5625 1175);
WIRE 16 -1 (-5625 1100)(-5625 1175);
WIRE 16 -1 (-5625 1175)(-5925 1175);
WIRE 16 -1 (-5925 1100)(-5925 1175);
WIRE 16 -1 (-5925 1175)(-6225 1175);
WIRE 16 -1 (-6225 1175)(-6225 1100);
WIRE 16 -1 (-6225 1175)(-6500 1175);
WIRE 16 -1 (-6500 1100)(-6500 1175);
WIRE 16 -1 (-6500 1175)(-6800 1175);
WIRE 16 -1 (-6800 1100)(-6800 1175);
WIRE 16 -1 (-6800 1175)(-7075 1175);
WIRE 16 -1 (-7075 1075)(-7075 1175);
WIRE 16 -1 (-7075 1175)(-7325 1175);
WIRE 16 -1 (-7325 1100)(-7325 1175);
WIRE 16 -1 (-7325 1175)(-7600 1175);
WIRE 16 -1 (-7600 1100)(-7600 1175);
WIRE 16 -1 (-7850 1175)(-7600 1175);
WIRE 16 -1 (-7850 1175)(-7850 1225);
WIRE 16 -1 (-7850 1175)(-7850 1100);
WIRE 16 -1 (-6625 2250)(-6625 2350);
WIRE 16 -1 (-6175 2375)(-6175 2550);
WIRE 16 -1 (-3525 875)(-3525 775);
WIRE 16 -1 (-7850 900)(-7850 750);
WIRE 16 -1 (-7850 750)(-7600 750);
WIRE 16 -1 (-7600 900)(-7600 750);
WIRE 16 -1 (-7325 750)(-7600 750);
WIRE 16 -1 (-7325 900)(-7325 750);
WIRE 16 -1 (-7075 750)(-7325 750);
WIRE 16 -1 (-7075 875)(-7075 750);
WIRE 16 -1 (-6800 750)(-7075 750);
WIRE 16 -1 (-6800 900)(-6800 750);
WIRE 16 -1 (-6500 750)(-6800 750);
WIRE 16 -1 (-6500 900)(-6500 750);
WIRE 16 -1 (-6225 750)(-6500 750);
WIRE 16 -1 (-6225 900)(-6225 750);
WIRE 16 -1 (-5925 750)(-6225 750);
WIRE 16 -1 (-5925 900)(-5925 750);
WIRE 16 -1 (-5625 750)(-5925 750);
WIRE 16 -1 (-5625 900)(-5625 750);
WIRE 16 -1 (-5350 750)(-5625 750);
WIRE 16 -1 (-5350 875)(-5350 750);
WIRE 16 -1 (-5075 750)(-5350 750);
WIRE 16 -1 (-5075 875)(-5075 750);
WIRE 16 -1 (-4900 750)(-5075 750);
WIRE 16 -1 (-4900 750)(-4825 750);
WIRE 16 -1 (-4900 750)(-4900 725);
WIRE 16 -1 (-4825 900)(-4825 750);
WIRE 16 -1 (-6600 4250)(-6600 4275);
WIRE 16 -1 (-4600 4125)(-4600 4300);
WIRE 16 -1 (-7200 4550)(-7050 4550);
WIRE 16 -1 (-7200 4775)(-7200 4550);
WIRE 16 -1 (-1000 1475)(-1000 1700);
WIRE 16 -1 (-1250 725)(-1050 725);
WIRE 16 -1 (-1250 675)(-1250 725);
WIRE 16 -1 (-700 675)(-700 725);
WIRE 16 -1 (-700 725)(-850 725);
WIRE 16 -1 (-2300 3500)(-2300 3450);
WIRE 16 -1 (-1725 3725)(-1725 3825);
WIRE 16 -1 (-1075 3775)(-1075 3700);
WIRE 16 -1 (-1075 3700)(-1400 3700);
WIRE 16 -1 (-1400 3700)(-1400 3825);
WIRE 16 -1 (-1400 3675)(-1400 3700);
WIRE 16 -1 (-825 3700)(-825 3825);
WIRE 16 -1 (-525 3825)(-525 3700);
WIRE 16 -1 (-1850 4100)(-1725 4100);
WIRE 16 -1 (-1725 4100)(-1400 4100);
WIRE 16 -1 (-1725 4025)(-1725 4100);
WIRE 16 -1 (-1400 4100)(-1075 4100);
WIRE 16 -1 (-1400 4100)(-1400 4025);
WIRE 16 -1 (-1075 3975)(-1075 4100);
WIRE 16 -1 (-1075 4100)(-825 4100);
WIRE 16 -1 (-825 4100)(-525 4100);
WIRE 16 -1 (-825 4100)(-825 4025);
WIRE 16 -1 (-450 4100)(-525 4100);
WIRE 16 -1 (-525 4100)(-525 4025);
WIRE 16 -1 (-250 4100)(-450 4100);
WIRE 16 -1 (-450 4175)(-450 4100);
WIRE 16 -1 (-250 4100)(-250 3425);
WIRE 16 -1 (-1000 3425)(-250 3425);
WIRE 16 -1 (-1000 3425)(-1000 3275);
WIRE 16 -1 (-4025 2275)(-3950 2275);
WIRE 16 -1 (-4025 2150)(-4025 2275);
WIRE 16 -1 (-4400 1800)(-4400 1650);
WIRE 16 -1 (-3875 1725)(-3875 1600);
WIRE 16 -1 (-4725 2325)(-4725 2250);
WIRE 16 -1 (-2950 2975)(-2725 2975);
WIRE 16 -1 (-2725 2975)(-2725 2925);
WIRE 16 -1 (-2950 2925)(-2725 2925);
WIRE 16 -1 (-2725 2925)(-2725 2875);
WIRE 16 -1 (-2950 2875)(-2725 2875);
WIRE 16 -1 (-2725 2875)(-2725 2825);
WIRE 16 -1 (-2950 2825)(-2725 2825);
WIRE 16 -1 (-2725 2825)(-2725 2775);
WIRE 16 -1 (-2950 2775)(-2725 2775);
WIRE 16 -1 (-2725 2775)(-2725 2725);
WIRE 16 -1 (-2950 2725)(-2725 2725);
WIRE 16 -1 (-2725 2725)(-2725 2675);
WIRE 16 -1 (-2950 2675)(-2725 2675);
WIRE 16 -1 (-2725 2675)(-2725 2625);
WIRE 16 -1 (-2950 2625)(-2725 2625);
WIRE 16 -1 (-2725 2625)(-2725 2575);
WIRE 16 -1 (-2950 2575)(-2725 2575);
WIRE 16 -1 (-2725 2575)(-2725 2525);
WIRE 16 -1 (-2950 2525)(-2725 2525);
WIRE 16 -1 (-2725 2525)(-2725 2475);
WIRE 16 -1 (-2950 2475)(-2725 2475);
WIRE 16 -1 (-2725 2475)(-2725 2425);
WIRE 16 -1 (-2950 2425)(-2725 2425);
WIRE 16 -1 (-2725 2425)(-2725 2375);
WIRE 16 -1 (-2950 2375)(-2725 2375);
WIRE 16 -1 (-2725 2375)(-2725 2325);
WIRE 16 -1 (-2950 2325)(-2725 2325);
WIRE 16 -1 (-2725 2325)(-2725 2275);
WIRE 16 -1 (-2950 2275)(-2725 2275);
WIRE 16 -1 (-2725 2275)(-2725 2225);
WIRE 16 -1 (-5375 2375)(-5375 2525);
WIRE 16 -1 (-3950 3175)(-5025 3175);
WIRE 16 -1 (-5025 3175)(-5025 3000);
WIRE 16 -1 (-4775 3650)(-4775 3575);
WIRE 16 -1 (-5500 4275)(-5500 4225);
WIRE 16 -1 (-5900 4275)(-5900 4225);
WIRE 16 -1 (-6300 4275)(-6300 4225);
WIRE 16 -1 (-5075 4275)(-5075 4225);
WIRE 16 -1 (-6175 2750)(-6175 3075);
WIRE 16 -1 (-6175 3075)(-5875 3075);
WIRE 16 -1 (-6625 3075)(-6175 3075);
WIRE 16 -1 (-7000 3075)(-6625 3075);
FORCEPROP 2 LAST SIG_NAME FM_PVPP_CPU0_EN
J 0
(-6901 3100);
DISPLAY 0.617021 (-6901 3100);
PAINT ORANGE (-6901 3100);
WIRE 16 -1 (-6625 2550)(-6625 3075);
WIRE 16 682 (-625 4325)(-625 4875);
WIRE 16 682 (-1675 4325)(-625 4325);
WIRE 16 682 (-625 4875)(-1675 4875);
WIRE 16 682 (-1675 4875)(-1675 4325);
WIRE 16 -1 (-2050 4100)(-2300 4100);
WIRE 16 -1 (-2675 4100)(-2300 4100);
FORCEPROP 2 LAST SIG_NAME VR_PVPP_ABC_PHASE
J 0
(-2660 4110);
DISPLAY 0.617021 (-2660 4110);
PAINT ORANGE (-2660 4110);
FORCEPROP 2 LASTPROP $XRERR UNIQUE?
J 0
(-2900 4110);
DISPLAY 0.638298 (-2900 4110);
PAINT MONO (-2900 4110);
DISPLAY INVISIBLE (-2900 4110);
WIRE 16 -1 (-2300 4050)(-2300 4100);
WIRE 16 -1 (-2675 4450)(-2675 4100);
WIRE 16 -1 (-2675 3725)(-2675 4100);
WIRE 16 -1 (-2675 3675)(-2675 3725);
WIRE 16 -1 (-2950 3725)(-2675 3725);
WIRE 16 -1 (-2925 4450)(-2675 4450);
WIRE 16 -1 (-2675 3625)(-2675 3675);
WIRE 16 -1 (-2950 3675)(-2675 3675);
WIRE 16 -1 (-2950 3625)(-2675 3625);
WIRE 16 -1 (-2675 3575)(-2675 3625);
WIRE 16 -1 (-2675 3525)(-2675 3575);
WIRE 16 -1 (-2950 3575)(-2675 3575);
WIRE 16 -1 (-2675 3475)(-2675 3525);
WIRE 16 -1 (-2950 3525)(-2675 3525);
WIRE 16 -1 (-2675 3425)(-2675 3475);
WIRE 16 -1 (-2950 3475)(-2675 3475);
WIRE 16 -1 (-2675 3375)(-2675 3425);
WIRE 16 -1 (-2950 3425)(-2675 3425);
WIRE 16 -1 (-2675 3275)(-2675 3375);
WIRE 16 -1 (-2950 3375)(-2675 3375);
WIRE 16 -1 (-2950 3275)(-2675 3275);
WIRE 16 2175 (-2825 4625)(-2825 4250);
WIRE 16 2175 (-4050 4625)(-2825 4625);
WIRE 16 2175 (-2825 4250)(-4050 4250);
WIRE 16 2175 (-4050 4250)(-4050 4625);
WIRE 16 -1 (-3950 4150)(-2900 4150);
WIRE 16 -1 (-3950 4450)(-3950 4150);
FORCEPROP 2 LAST SIG_NAME VR_PVPP_ABC_BOOT
J 0
(-3860 4185);
DISPLAY 0.617021 (-3860 4185);
PAINT ORANGE (-3860 4185);
FORCEPROP 2 LASTPROP $XRERR UNIQUE?
J 0
(-4100 4185);
DISPLAY 0.638298 (-4100 4185);
PAINT MONO (-4100 4185);
DISPLAY INVISIBLE (-4100 4185);
WIRE 16 -1 (-2900 4150)(-2900 3825);
WIRE 16 -1 (-2900 3825)(-2950 3825);
WIRE 16 -1 (-3825 4450)(-3950 4450);
WIRE 16 -1 (-3125 4450)(-3625 4450);
FORCEPROP 2 LAST SIG_NAME VR_PVPP_ABC_BOOT_R
J 0
(-3605 4460);
DISPLAY 0.617021 (-3605 4460);
PAINT ORANGE (-3605 4460);
FORCEPROP 2 LASTPROP $XRERR UNIQUE?
J 0
(-3845 4460);
DISPLAY 0.638298 (-3845 4460);
PAINT MONO (-3845 4460);
DISPLAY INVISIBLE (-3845 4460);
WIRE 16 -1 (-1000 3050)(-1000 3075);
WIRE 16 -1 (-675 3050)(-1000 3050);
WIRE 16 -1 (-1000 2525)(-1000 3050);
FORCEPROP 0 LAST SIG_NAME VSENSE_PVPP_ABC
R 1
J 0
(-1010 2560);
DISPLAY 0.617021 (-1010 2560);
PAINT ORANGE (-1010 2560);
FORCEPROP 2 LASTPROP $XRERR UNIQUE?
J 0
(-1250 2560);
DISPLAY 0.638298 (-1250 2560);
PAINT MONO (-1250 2560);
DISPLAY INVISIBLE (-1250 2560);
WIRE 16 -1 (-675 2975)(-675 3050);
WIRE 16 -1 (-675 2425)(-675 2775);
FORCEPROP 0 LAST SIG_NAME VR_COMP_PVPP_ABC
R 1
J 0
(-685 2410);
DISPLAY 0.617021 (-685 2410);
PAINT ORANGE (-685 2410);
FORCEPROP 2 LASTPROP $XRERR UNIQUE?
J 0
(-925 2410);
DISPLAY 0.638298 (-925 2410);
PAINT MONO (-925 2410);
DISPLAY INVISIBLE (-925 2410);
WIRE 16 -1 (-675 2225)(-675 2075);
WIRE 16 -1 (-675 2075)(-1000 2075);
WIRE 16 -1 (-1000 2325)(-1000 2075);
WIRE 16 -1 (-1000 2075)(-1000 1975);
WIRE 16 -1 (-1000 1975)(-1000 1900);
WIRE 16 -1 (-1525 1975)(-1000 1975);
FORCEPROP 0 LAST SIG_NAME VR_FB_PVPP_ABC
J 0
(-1485 1985);
DISPLAY 0.617021 (-1485 1985);
PAINT ORANGE (-1485 1985);
FORCEPROP 2 LASTPROP $XRERR UNIQUE?
J 0
(-1725 1985);
DISPLAY 0.638298 (-1725 1985);
PAINT MONO (-1725 1985);
DISPLAY INVISIBLE (-1725 1985);
WIRE 16 -1 (-1525 1975)(-1525 3175);
WIRE 16 -1 (-1525 3175)(-1625 3175);
WIRE 16 -1 (-1625 3075)(-1625 3175);
WIRE 16 -1 (-2950 3175)(-1625 3175);
WIRE 16 -1 (-1975 3075)(-1625 3075);
WIRE 16 -1 (-1625 2700)(-1625 3075);
WIRE 16 -1 (-1625 2700)(-1700 2700);
WIRE 16 2175 (-1075 3375)(-425 3375);
WIRE 16 2175 (-1075 1575)(-1075 3375);
WIRE 16 2175 (-425 3375)(-425 1575);
WIRE 16 2175 (-1075 1575)(-425 1575);
WIRE 16 -1 (-1900 2700)(-2400 2700);
FORCEPROP 0 LAST SIG_NAME VR_COMP_RC_PVPP_ABC
J 0
(-2385 2710);
DISPLAY 0.617021 (-2385 2710);
PAINT ORANGE (-2385 2710);
FORCEPROP 2 LASTPROP $XRERR UNIQUE?
J 0
(-2625 2710);
DISPLAY 0.638298 (-2625 2710);
PAINT MONO (-2625 2710);
DISPLAY INVISIBLE (-2625 2710);
WIRE 16 -1 (-2300 3700)(-2300 3850);
FORCEPROP 2 LAST SIG_NAME VR_PVPP_ABC_SNUB
J 0
(-2285 3760);
DISPLAY 0.617021 (-2285 3760);
PAINT ORANGE (-2285 3760);
FORCEPROP 2 LASTPROP $XRERR UNIQUE?
J 0
(-2525 3760);
DISPLAY 0.638298 (-2525 3760);
PAINT MONO (-2525 3760);
DISPLAY INVISIBLE (-2525 3760);
WIRE 16 -1 (-2950 3075)(-2650 3075);
WIRE 16 -1 (-2650 3075)(-2175 3075);
WIRE 16 -1 (-2650 2700)(-2650 3075);
FORCEPROP 0 LAST SIG_NAME VR_COMP_PVPP_ABC_3
J 0
(-2810 3085);
DISPLAY 0.617021 (-2810 3085);
PAINT ORANGE (-2810 3085);
FORCEPROP 2 LASTPROP $XRERR UNIQUE?
J 0
(-3050 3085);
DISPLAY 0.638298 (-3050 3085);
PAINT MONO (-3050 3085);
DISPLAY INVISIBLE (-3050 3085);
WIRE 16 -1 (-2600 2700)(-2650 2700);
WIRE 16 -1 (-2450 1225)(-2900 1225);
FORCEPROP 2 LAST SIG_NAME PWRGD_PVPP_ABC
J 0
(-2835 1235);
DISPLAY 0.617021 (-2835 1235);
PAINT ORANGE (-2835 1235);
WIRE 16 -1 (-3525 1075)(-3525 1225);
WIRE 16 -1 (-3100 1225)(-3525 1225);
FORCEPROP 2 LAST SIG_NAME PWRGD_PVPP_ABC_R
J 0
(-3610 1235);
DISPLAY 0.617021 (-3610 1235);
PAINT ORANGE (-3610 1235);
FORCEPROP 2 LASTPROP $XRERR UNIQUE?
J 0
(-3850 1235);
DISPLAY 0.638298 (-3850 1235);
PAINT MONO (-3850 1235);
DISPLAY INVISIBLE (-3850 1235);
WIRE 16 -1 (-3525 1225)(-3875 1225);
WIRE 16 -1 (-3875 1400)(-3875 1225);
WIRE 16 -1 (-3875 1225)(-4200 1225);
WIRE 16 -1 (-4200 1225)(-4200 2775);
WIRE 16 -1 (-3950 2775)(-4200 2775);
WIRE 16 -1 (-3950 3375)(-4375 3375);
WIRE 16 -1 (-4375 3375)(-4375 3425);
WIRE 16 -1 (-3950 3425)(-4375 3425);
WIRE 16 -1 (-4375 3425)(-4375 3475);
WIRE 16 -1 (-3950 3475)(-4375 3475);
WIRE 16 -1 (-4375 3475)(-4375 3525);
WIRE 16 -1 (-3950 3525)(-4375 3525);
WIRE 16 -1 (-4375 3525)(-4375 3575);
WIRE 16 -1 (-3950 3575)(-4375 3575);
WIRE 16 -1 (-4375 3575)(-4375 3625);
WIRE 16 -1 (-3950 3625)(-4375 3625);
WIRE 16 -1 (-4375 3625)(-4375 3675);
WIRE 16 -1 (-3950 3675)(-4375 3675);
WIRE 16 -1 (-4375 3675)(-4375 3725);
WIRE 16 -1 (-4375 3725)(-3950 3725);
WIRE 16 -1 (-4375 3825)(-4375 3725);
WIRE 16 -1 (-3950 3825)(-4375 3825);
WIRE 16 -1 (-4375 3950)(-4375 3825);
WIRE 16 -1 (-4375 4550)(-4375 3950);
WIRE 16 -1 (-4775 3950)(-4375 3950);
WIRE 16 -1 (-4775 3850)(-4775 3950);
WIRE 16 -1 (-4600 4550)(-4375 4550);
WIRE 16 -1 (-4600 4500)(-4600 4550);
WIRE 16 -1 (-4600 4550)(-5075 4550);
WIRE 16 -1 (-5075 4475)(-5075 4550);
WIRE 16 -1 (-5075 4550)(-5500 4550);
WIRE 16 -1 (-5500 4475)(-5500 4550);
WIRE 16 -1 (-5500 4550)(-5900 4550);
FORCEPROP 0 LAST SIG_NAME VR_FET_SW_P12V_STBY_PVPP_ABC
J 0
(-5560 4560);
DISPLAY 0.617021 (-5560 4560);
PAINT ORANGE (-5560 4560);
FORCEPROP 2 LASTPROP $XRERR UNIQUE?
J 0
(-5800 4560);
DISPLAY 0.638298 (-5800 4560);
PAINT MONO (-5800 4560);
DISPLAY INVISIBLE (-5800 4560);
WIRE 16 -1 (-5900 4475)(-5900 4550);
WIRE 16 -1 (-5900 4550)(-6300 4550);
WIRE 16 -1 (-6300 4475)(-6300 4550);
WIRE 16 -1 (-6300 4550)(-6600 4550);
WIRE 16 -1 (-6600 4475)(-6600 4550);
WIRE 16 -1 (-6850 4550)(-6600 4550);
WIRE 16 -1 (-5375 3275)(-3950 3275);
FORCEPROP 0 LAST SIG_NAME VR_VB_PVPP_ABC
J 0
(-5085 3285);
DISPLAY 0.617021 (-5085 3285);
PAINT ORANGE (-5085 3285);
FORCEPROP 2 LASTPROP $XRERR UNIQUE?
J 0
(-5325 3285);
DISPLAY 0.638298 (-5325 3285);
PAINT MONO (-5325 3285);
DISPLAY INVISIBLE (-5325 3285);
WIRE 16 -1 (-5375 2725)(-5375 3275);
WIRE 16 -1 (-4400 2875)(-3950 2875);
WIRE 16 -1 (-4400 2000)(-4400 2875);
FORCEPROP 2 LAST SIG_NAME VR_PVPP_ABC_ISET
R 1
J 0
(-4410 2360);
DISPLAY 0.617021 (-4410 2360);
PAINT ORANGE (-4410 2360);
FORCEPROP 2 LASTPROP $XRERR UNIQUE?
J 0
(-4650 2360);
DISPLAY 0.638298 (-4650 2360);
PAINT MONO (-4650 2360);
DISPLAY INVISIBLE (-4650 2360);
WIRE 16 -1 (-3950 2975)(-4725 2975);
WIRE 16 -1 (-4725 2975)(-4725 2525);
FORCEPROP 2 LAST SIG_NAME VR_PVPP_ABC_SS
R 1
J 0
(-4735 2535);
DISPLAY 0.617021 (-4735 2535);
PAINT ORANGE (-4735 2535);
FORCEPROP 2 LASTPROP $XRERR UNIQUE?
J 0
(-4975 2535);
DISPLAY 0.638298 (-4975 2535);
PAINT MONO (-4975 2535);
DISPLAY INVISIBLE (-4975 2535);
WIRE 16 -1 (-5675 3075)(-3950 3075);
FORCEPROP 2 LAST SIG_NAME FM_PVPP_PVDDQ_CPU0_EN_ABC
J 0
(-4926 3100);
DISPLAY 0.617021 (-4926 3100);
PAINT ORANGE (-4926 3100);
FORCEPROP 2 LASTPROP $XRERR UNIQUE?
J 0
(-5166 3100);
DISPLAY 0.638298 (-5166 3100);
PAINT MONO (-5166 3100);
DISPLAY INVISIBLE (-5166 3100);
WIRE 16 2175 (-4675 4600)(-4675 4150);
WIRE 16 2175 (-6750 4600)(-4675 4600);
WIRE 16 2175 (-4675 4150)(-6750 4150);
WIRE 16 2175 (-6750 4150)(-6750 4600);
WIRE 16 2175 (-4550 1425)(-4550 625);
WIRE 16 2175 (-7975 1425)(-4550 1425);
WIRE 16 2175 (-4550 625)(-7975 625);
WIRE 16 -1 (-7975 625)(-7975 1425);
DOT 1 (-7600 750);
DOT 1 (-7325 750);
DOT 1 (-7850 1175);
DOT 1 (-7600 1175);
DOT 1 (-7325 1175);
DOT 1 (-7075 750);
DOT 1 (-6800 750);
DOT 1 (-6500 750);
DOT 1 (-6225 750);
DOT 1 (-7075 1175);
DOT 1 (-6800 1175);
DOT 1 (-6500 1175);
DOT 1 (-6225 1175);
DOT 1 (-6625 3075);
DOT 1 (-6175 3075);
DOT 1 (-5925 750);
DOT 1 (-5625 750);
DOT 1 (-5350 750);
DOT 1 (-5925 1175);
DOT 1 (-5625 1175);
DOT 1 (-5350 1175);
DOT 1 (-5075 750);
DOT 1 (-4900 750);
DOT 1 (-5075 1175);
DOT 1 (-4375 3425);
DOT 1 (-4375 3475);
DOT 1 (-4375 3525);
DOT 1 (-4375 3575);
DOT 1 (-4375 3625);
DOT 1 (-4375 3675);
DOT 1 (-4375 3725);
DOT 1 (-4375 3825);
DOT 1 (-4375 3950);
DOT 1 (-6600 4550);
DOT 1 (-6300 4550);
DOT 1 (-5900 4550);
DOT 1 (-5500 4550);
DOT 1 (-5075 4550);
DOT 1 (-4600 4550);
DOT 1 (-3875 1225);
DOT 1 (-3525 1225);
DOT 1 (-2725 2275);
DOT 1 (-2725 2325);
DOT 1 (-2725 2375);
DOT 1 (-2725 2425);
DOT 1 (-2725 2475);
DOT 1 (-2725 2525);
DOT 1 (-2725 2575);
DOT 1 (-2725 2625);
DOT 1 (-2725 2675);
DOT 1 (-2725 2775);
DOT 1 (-2725 2725);
DOT 1 (-2725 2825);
DOT 1 (-2725 2875);
DOT 1 (-2725 2925);
DOT 1 (-2650 3075);
DOT 1 (-2675 3575);
DOT 1 (-2675 3525);
DOT 1 (-2675 3375);
DOT 1 (-2675 3475);
DOT 1 (-2675 3425);
DOT 1 (-2675 3725);
DOT 1 (-2675 3625);
DOT 1 (-2675 3675);
DOT 1 (-1000 1975);
DOT 1 (-1625 3075);
DOT 1 (-1625 3175);
DOT 1 (-1400 3700);
DOT 1 (-1000 2075);
DOT 1 (-1000 3050);
DOT 1 (-2300 4100);
DOT 1 (-825 4100);
DOT 1 (-1725 4100);
DOT 1 (-450 4100);
DOT 1 (-2675 4100);
DOT 1 (-1400 4100);
DOT 1 (-525 4100);
DOT 1 (-1075 4100);
FORCENOTE
BOM_COST: PVPP_ABC_VR
(-7225 150) 0;
DISPLAY LEFT (-7225 150);
DISPLAY 0.787234 (-7225 150);
PAINT PURPLE (-7225 150);
FORCENOTE
ROOM = PVPP_ABC_VR
(-7225 200) 0;
DISPLAY LEFT (-7225 200);
DISPLAY 0.787234 (-7225 200);
PAINT PURPLE (-7225 200);
FORCENOTE
CAPS TO BE PLACED BETWEEN DIMMS
(-7495 1330) 0;
DISPLAY LEFT (-7495 1330);
DISPLAY 1.021277 (-7495 1330);
PAINT PURPLE (-7495 1330);
FORCENOTE
25A OC
(-4845 1855) 0;
DISPLAY LEFT (-4845 1855);
PAINT PURPLE (-4845 1855);
FORCENOTE
(0.4V/MS)
(-5045 2430) 0;
DISPLAY LEFT (-5045 2430);
PAINT PURPLE (-5045 2430);
FORCENOTE
6.25MS
(-4995 2480) 0;
DISPLAY LEFT (-4995 2480);
PAINT PURPLE (-4995 2480);
FORCENOTE
COMPENSATION TYPE III
(-2625 2400) 0;
DISPLAY LEFT (-2625 2400);
DISPLAY 1.042553 (-2625 2400);
PAINT PURPLE (-2625 2400);
FORCENOTE
CONNECT AT SINGLE
(-1250 925) 0;
DISPLAY LEFT (-1250 925);
DISPLAY 1.042553 (-1250 925);
PAINT PURPLE (-1250 925);
FORCENOTE
POINT ONLY TOP TO L2
(-1300 875) 0;
DISPLAY LEFT (-1300 875);
DISPLAY 1.042553 (-1300 875);
PAINT PURPLE (-1300 875);
FORCENOTE
SPOF
(-855 3225) 0;
DISPLAY LEFT (-855 3225);
DISPLAY 2.340426 (-855 3225);
PAINT PURPLE (-855 3225);
FORCENOTE
SPOF
(-4050 4675) 0;
DISPLAY LEFT (-4050 4675);
DISPLAY 1.659574 (-4050 4675);
PAINT PURPLE (-4050 4675);
FORCENOTE
PLACE ON
(-3750 4675) 0;
DISPLAY LEFT (-3750 4675);
DISPLAY 1.042553 (-3750 4675);
PAINT PURPLE (-3750 4675);
FORCENOTE
TOP LAYER
(-3375 4675) 0;
DISPLAY LEFT (-3375 4675);
DISPLAY 1.042553 (-3375 4675);
PAINT PURPLE (-3375 4675);
FORCENOTE
IOUT TDC = 8A
(-1650 4600) 0;
DISPLAY LEFT (-1650 4600);
DISPLAY 1.021277 (-1650 4600);
PAINT PURPLE (-1650 4600);
FORCENOTE
IOUT PK = 15A
(-1650 4550) 0;
DISPLAY LEFT (-1650 4550);
DISPLAY 1.021277 (-1650 4550);
PAINT PURPLE (-1650 4550);
FORCENOTE
VOUT = 2.5V
(-1650 4800) 0;
DISPLAY LEFT (-1650 4800);
DISPLAY 1.021277 (-1650 4800);
PAINT PURPLE (-1650 4800);
FORCENOTE
AC & RIPPLE TOL = +3.5%, -7.3%
(-1650 4650) 0;
DISPLAY LEFT (-1650 4650);
DISPLAY 1.021277 (-1650 4650);
PAINT PURPLE (-1650 4650);
FORCENOTE
DC TOL = +/-1.5%
(-1650 4700) 0;
DISPLAY LEFT (-1650 4700);
DISPLAY 1.021277 (-1650 4700);
PAINT PURPLE (-1650 4700);
FORCENOTE
RIPPLE GUIDELINE = +/- 1.0%
(-1650 4750) 0;
DISPLAY LEFT (-1650 4750);
DISPLAY 1.021277 (-1650 4750);
PAINT PURPLE (-1650 4750);
FORCENOTE
IOUT STEP = 3A
(-1650 4500) 0;
DISPLAY LEFT (-1650 4500);
DISPLAY 1.021277 (-1650 4500);
PAINT PURPLE (-1650 4500);
FORCENOTE
IOUT DI/DT = 25A/US
(-1650 4450) 0;
DISPLAY LEFT (-1650 4450);
DISPLAY 1.021277 (-1650 4450);
PAINT PURPLE (-1650 4450);
FORCENOTE
SW FREQ =  500KHZ
(-1650 4400) 0;
DISPLAY LEFT (-1650 4400);
DISPLAY 1.021277 (-1650 4400);
PAINT PURPLE (-1650 4400);
QUIT
